FILE_TYPE = MACRO_DRAWING;
SET COLOR_WIRE YELLOW;
SET COLOR_PROP ORANGE;
SET COLOR_DOT WHITE;
SET COLOR_ARC YELLOW;
SET COLOR_BODY GREEN;
SET COLOR_NOTE PURPLE;
SET PROP_DISPLAY VALUE;
SET PAGE_NUMBER P107;
FORCEADD OFFPAGE..5
(-8300 1875);
FORCEPROP 2 LAST $XR0 47 
J 0
(-8554 1875);
DISPLAY 0.638298 (-8554 1875);
PAINT MONO (-8554 1875);
FORCEPROP 2 LAST CDS_LIB mstr_standard
J 0
(-8300 1875);
DISPLAY 0.808511 (-8300 1875);
DISPLAY INVISIBLE (-8300 1875);
FORCEPROP 1 LAST OFFPAGE TRUE
J 0
(-7975 1750);
DISPLAY 0.872340 (-7975 1750);
PAINT GREEN (-7975 1750);
DISPLAY INVISIBLE (-7975 1750);
FORCEPROP 1 LAST COMMENT_BODY TRUE
J 0
(-8200 1800);
DISPLAY 0.872340 (-8200 1800);
PAINT GREEN (-8200 1800);
DISPLAY INVISIBLE (-8200 1800);
FORCEPROP 2 LAST PATH I1
J 0
(-8550 1925);
DISPLAY 1.021277 (-8550 1925);
DISPLAY INVISIBLE (-8550 1925);
FORCEADD OFFPAGE..6
(-8300 3525);
FORCEPROP 2 LAST $XR0 47 
J 0
(-8549 3525);
DISPLAY 0.638298 (-8549 3525);
PAINT MONO (-8549 3525);
FORCEPROP 2 LAST CDS_LIB mstr_standard
J 0
(-8300 3525);
DISPLAY 0.723404 (-8300 3525);
PAINT MONO (-8300 3525);
DISPLAY INVISIBLE (-8300 3525);
FORCEPROP 1 LAST OFFPAGE TRUE
J 0
(-7975 3400);
DISPLAY 0.872340 (-7975 3400);
PAINT GREEN (-7975 3400);
DISPLAY INVISIBLE (-7975 3400);
FORCEPROP 1 LAST COMMENT_BODY TRUE
J 0
(-8200 3450);
DISPLAY 0.872340 (-8200 3450);
PAINT GREEN (-8200 3450);
DISPLAY INVISIBLE (-8200 3450);
FORCEPROP 2 LAST PATH I10
J 0
(-8575 3575);
DISPLAY 1.021277 (-8575 3575);
DISPLAY INVISIBLE (-8575 3575);
FORCEADD TAP..1
(-6000 4175);
FORCEPROP 3 LASTPIN (-6050 4175) SIG_NAME M_K_CPU1_SA_DQ<8>
J 0
(-6040 4185);
DISPLAY 0.659574 (-6040 4185);
PAINT MONO (-6040 4185);
DISPLAY INVISIBLE (-6040 4185);
FORCEPROP 1 LASTPIN (-6050 4175) BN 8
J 0
(-6062 4183);
DISPLAY 0.489362 (-6062 4183);
PAINT GREEN (-6062 4183);
FORCEPROP 2 LAST CDS_LIB mstr_standard
J 0
(-6000 4175);
DISPLAY 0.723404 (-6000 4175);
PAINT MONO (-6000 4175);
DISPLAY INVISIBLE (-6000 4175);
FORCEPROP 1 LAST BODY_TYPE PLUMBING
J 0
(-6000 4225);
DISPLAY 0.872340 (-6000 4225);
PAINT GREEN (-6000 4225);
DISPLAY INVISIBLE (-6000 4225);
FORCEPROP 1 LAST HDL_TAP TRUE
J 0
(-5675 4050);
DISPLAY 0.872340 (-5675 4050);
DISPLAY INVISIBLE (-5675 4050);
FORCEPROP 1 LAST PATH I100
J 0
(-6002 4175);
DISPLAY 0.872340 (-6002 4175);
PAINT GREEN (-6002 4175);
DISPLAY INVISIBLE (-6002 4175);
FORCEADD TAP..1
(-6000 4225);
FORCEPROP 3 LASTPIN (-6050 4225) SIG_NAME M_K_CPU1_SA_DQ<9>
J 0
(-6040 4235);
DISPLAY 0.659574 (-6040 4235);
PAINT MONO (-6040 4235);
DISPLAY INVISIBLE (-6040 4235);
FORCEPROP 1 LASTPIN (-6050 4225) BN 9
J 0
(-6062 4233);
DISPLAY 0.489362 (-6062 4233);
PAINT GREEN (-6062 4233);
FORCEPROP 2 LAST CDS_LIB mstr_standard
J 0
(-6000 4225);
DISPLAY 0.723404 (-6000 4225);
PAINT MONO (-6000 4225);
DISPLAY INVISIBLE (-6000 4225);
FORCEPROP 1 LAST BODY_TYPE PLUMBING
J 0
(-6000 4275);
DISPLAY 0.872340 (-6000 4275);
PAINT GREEN (-6000 4275);
DISPLAY INVISIBLE (-6000 4275);
FORCEPROP 1 LAST HDL_TAP TRUE
J 0
(-5675 4100);
DISPLAY 0.872340 (-5675 4100);
DISPLAY INVISIBLE (-5675 4100);
FORCEPROP 1 LAST PATH I101
J 0
(-6002 4225);
DISPLAY 0.872340 (-6002 4225);
PAINT GREEN (-6002 4225);
DISPLAY INVISIBLE (-6002 4225);
FORCEADD TAP..1
(-6000 4275);
FORCEPROP 3 LASTPIN (-6050 4275) SIG_NAME M_K_CPU1_SA_DQ<10>
J 0
(-6040 4285);
DISPLAY 0.659574 (-6040 4285);
PAINT MONO (-6040 4285);
DISPLAY INVISIBLE (-6040 4285);
FORCEPROP 1 LASTPIN (-6050 4275) BN 10
J 0
(-6062 4283);
DISPLAY 0.489362 (-6062 4283);
PAINT GREEN (-6062 4283);
FORCEPROP 2 LAST CDS_LIB mstr_standard
J 0
(-6000 4275);
DISPLAY 0.723404 (-6000 4275);
PAINT MONO (-6000 4275);
DISPLAY INVISIBLE (-6000 4275);
FORCEPROP 1 LAST BODY_TYPE PLUMBING
J 0
(-6000 4325);
DISPLAY 0.872340 (-6000 4325);
PAINT GREEN (-6000 4325);
DISPLAY INVISIBLE (-6000 4325);
FORCEPROP 1 LAST HDL_TAP TRUE
J 0
(-5675 4150);
DISPLAY 0.872340 (-5675 4150);
DISPLAY INVISIBLE (-5675 4150);
FORCEPROP 1 LAST PATH I102
J 0
(-6002 4275);
DISPLAY 0.872340 (-6002 4275);
PAINT GREEN (-6002 4275);
DISPLAY INVISIBLE (-6002 4275);
FORCEADD TAP..1
(-6000 4375);
FORCEPROP 3 LASTPIN (-6050 4375) SIG_NAME M_K_CPU1_SA_DQ<12>
J 0
(-6040 4385);
DISPLAY 0.659574 (-6040 4385);
PAINT MONO (-6040 4385);
DISPLAY INVISIBLE (-6040 4385);
FORCEPROP 1 LASTPIN (-6050 4375) BN 12
J 0
(-6062 4383);
DISPLAY 0.489362 (-6062 4383);
PAINT GREEN (-6062 4383);
FORCEPROP 2 LAST CDS_LIB mstr_standard
J 0
(-6000 4375);
DISPLAY 0.723404 (-6000 4375);
PAINT MONO (-6000 4375);
DISPLAY INVISIBLE (-6000 4375);
FORCEPROP 1 LAST BODY_TYPE PLUMBING
J 0
(-6000 4425);
DISPLAY 0.872340 (-6000 4425);
PAINT GREEN (-6000 4425);
DISPLAY INVISIBLE (-6000 4425);
FORCEPROP 1 LAST HDL_TAP TRUE
J 0
(-5675 4250);
DISPLAY 0.872340 (-5675 4250);
DISPLAY INVISIBLE (-5675 4250);
FORCEPROP 1 LAST PATH I103
J 0
(-6002 4375);
DISPLAY 0.872340 (-6002 4375);
PAINT GREEN (-6002 4375);
DISPLAY INVISIBLE (-6002 4375);
FORCEADD TAP..1
(-6000 4325);
FORCEPROP 3 LASTPIN (-6050 4325) SIG_NAME M_K_CPU1_SA_DQ<11>
J 0
(-6040 4335);
DISPLAY 0.659574 (-6040 4335);
PAINT MONO (-6040 4335);
DISPLAY INVISIBLE (-6040 4335);
FORCEPROP 1 LASTPIN (-6050 4325) BN 11
J 0
(-6062 4333);
DISPLAY 0.489362 (-6062 4333);
PAINT GREEN (-6062 4333);
FORCEPROP 2 LAST CDS_LIB mstr_standard
J 0
(-6000 4325);
DISPLAY 0.723404 (-6000 4325);
PAINT MONO (-6000 4325);
DISPLAY INVISIBLE (-6000 4325);
FORCEPROP 1 LAST BODY_TYPE PLUMBING
J 0
(-6000 4375);
DISPLAY 0.872340 (-6000 4375);
PAINT GREEN (-6000 4375);
DISPLAY INVISIBLE (-6000 4375);
FORCEPROP 1 LAST HDL_TAP TRUE
J 0
(-5675 4200);
DISPLAY 0.872340 (-5675 4200);
DISPLAY INVISIBLE (-5675 4200);
FORCEPROP 1 LAST PATH I104
J 0
(-6002 4325);
DISPLAY 0.872340 (-6002 4325);
PAINT GREEN (-6002 4325);
DISPLAY INVISIBLE (-6002 4325);
FORCEADD TAP..1
(-6000 4425);
FORCEPROP 3 LASTPIN (-6050 4425) SIG_NAME M_K_CPU1_SA_DQ<13>
J 0
(-6040 4435);
DISPLAY 0.659574 (-6040 4435);
PAINT MONO (-6040 4435);
DISPLAY INVISIBLE (-6040 4435);
FORCEPROP 1 LASTPIN (-6050 4425) BN 13
J 0
(-6062 4433);
DISPLAY 0.489362 (-6062 4433);
PAINT GREEN (-6062 4433);
FORCEPROP 2 LAST CDS_LIB mstr_standard
J 0
(-6000 4425);
DISPLAY 0.723404 (-6000 4425);
PAINT MONO (-6000 4425);
DISPLAY INVISIBLE (-6000 4425);
FORCEPROP 1 LAST BODY_TYPE PLUMBING
J 0
(-6000 4475);
DISPLAY 0.872340 (-6000 4475);
PAINT GREEN (-6000 4475);
DISPLAY INVISIBLE (-6000 4475);
FORCEPROP 1 LAST HDL_TAP TRUE
J 0
(-5675 4300);
DISPLAY 0.872340 (-5675 4300);
DISPLAY INVISIBLE (-5675 4300);
FORCEPROP 1 LAST PATH I105
J 0
(-6002 4425);
DISPLAY 0.872340 (-6002 4425);
PAINT GREEN (-6002 4425);
DISPLAY INVISIBLE (-6002 4425);
FORCEADD TAP..1
(-6000 4475);
FORCEPROP 3 LASTPIN (-6050 4475) SIG_NAME M_K_CPU1_SA_DQ<14>
J 0
(-6040 4485);
DISPLAY 0.659574 (-6040 4485);
PAINT MONO (-6040 4485);
DISPLAY INVISIBLE (-6040 4485);
FORCEPROP 1 LASTPIN (-6050 4475) BN 14
J 0
(-6062 4483);
DISPLAY 0.489362 (-6062 4483);
PAINT GREEN (-6062 4483);
FORCEPROP 2 LAST CDS_LIB mstr_standard
J 0
(-6000 4475);
DISPLAY 0.723404 (-6000 4475);
PAINT MONO (-6000 4475);
DISPLAY INVISIBLE (-6000 4475);
FORCEPROP 1 LAST BODY_TYPE PLUMBING
J 0
(-6000 4525);
DISPLAY 0.872340 (-6000 4525);
PAINT GREEN (-6000 4525);
DISPLAY INVISIBLE (-6000 4525);
FORCEPROP 1 LAST HDL_TAP TRUE
J 0
(-5675 4350);
DISPLAY 0.872340 (-5675 4350);
DISPLAY INVISIBLE (-5675 4350);
FORCEPROP 1 LAST PATH I106
J 0
(-6002 4475);
DISPLAY 0.872340 (-6002 4475);
PAINT GREEN (-6002 4475);
DISPLAY INVISIBLE (-6002 4475);
FORCEADD TAP..1
(-6000 4525);
FORCEPROP 3 LASTPIN (-6050 4525) SIG_NAME M_K_CPU1_SA_DQ<15>
J 0
(-6040 4535);
DISPLAY 0.659574 (-6040 4535);
PAINT MONO (-6040 4535);
DISPLAY INVISIBLE (-6040 4535);
FORCEPROP 1 LASTPIN (-6050 4525) BN 15
J 0
(-6062 4533);
DISPLAY 0.489362 (-6062 4533);
PAINT GREEN (-6062 4533);
FORCEPROP 2 LAST CDS_LIB mstr_standard
J 0
(-6000 4525);
DISPLAY 0.723404 (-6000 4525);
PAINT MONO (-6000 4525);
DISPLAY INVISIBLE (-6000 4525);
FORCEPROP 1 LAST BODY_TYPE PLUMBING
J 0
(-6000 4575);
DISPLAY 0.872340 (-6000 4575);
PAINT GREEN (-6000 4575);
DISPLAY INVISIBLE (-6000 4575);
FORCEPROP 1 LAST HDL_TAP TRUE
J 0
(-5675 4400);
DISPLAY 0.872340 (-5675 4400);
DISPLAY INVISIBLE (-5675 4400);
FORCEPROP 1 LAST PATH I107
J 0
(-6002 4525);
DISPLAY 0.872340 (-6002 4525);
PAINT GREEN (-6002 4525);
DISPLAY INVISIBLE (-6002 4525);
FORCEADD TAP..1
(-6000 4575);
FORCEPROP 3 LASTPIN (-6050 4575) SIG_NAME M_K_CPU1_SA_DQ<16>
J 0
(-6040 4585);
DISPLAY 0.659574 (-6040 4585);
PAINT MONO (-6040 4585);
DISPLAY INVISIBLE (-6040 4585);
FORCEPROP 1 LASTPIN (-6050 4575) BN 16
J 0
(-6062 4583);
DISPLAY 0.489362 (-6062 4583);
PAINT GREEN (-6062 4583);
FORCEPROP 2 LAST CDS_LIB mstr_standard
J 0
(-6000 4575);
DISPLAY 0.723404 (-6000 4575);
PAINT MONO (-6000 4575);
DISPLAY INVISIBLE (-6000 4575);
FORCEPROP 1 LAST BODY_TYPE PLUMBING
J 0
(-6000 4625);
DISPLAY 0.872340 (-6000 4625);
PAINT GREEN (-6000 4625);
DISPLAY INVISIBLE (-6000 4625);
FORCEPROP 1 LAST HDL_TAP TRUE
J 0
(-5675 4450);
DISPLAY 0.872340 (-5675 4450);
DISPLAY INVISIBLE (-5675 4450);
FORCEPROP 1 LAST PATH I108
J 0
(-6002 4575);
DISPLAY 0.872340 (-6002 4575);
PAINT GREEN (-6002 4575);
DISPLAY INVISIBLE (-6002 4575);
FORCEADD TAP..1
(-6000 4675);
FORCEPROP 3 LASTPIN (-6050 4675) SIG_NAME M_K_CPU1_SA_DQ<18>
J 0
(-6040 4685);
DISPLAY 0.659574 (-6040 4685);
PAINT MONO (-6040 4685);
DISPLAY INVISIBLE (-6040 4685);
FORCEPROP 1 LASTPIN (-6050 4675) BN 18
J 0
(-6062 4683);
DISPLAY 0.489362 (-6062 4683);
PAINT GREEN (-6062 4683);
FORCEPROP 2 LAST CDS_LIB mstr_standard
J 0
(-6000 4675);
DISPLAY 0.723404 (-6000 4675);
PAINT MONO (-6000 4675);
DISPLAY INVISIBLE (-6000 4675);
FORCEPROP 1 LAST BODY_TYPE PLUMBING
J 0
(-6000 4725);
DISPLAY 0.872340 (-6000 4725);
PAINT GREEN (-6000 4725);
DISPLAY INVISIBLE (-6000 4725);
FORCEPROP 1 LAST HDL_TAP TRUE
J 0
(-5675 4550);
DISPLAY 0.872340 (-5675 4550);
DISPLAY INVISIBLE (-5675 4550);
FORCEPROP 1 LAST PATH I109
J 0
(-6002 4675);
DISPLAY 0.872340 (-6002 4675);
PAINT GREEN (-6002 4675);
DISPLAY INVISIBLE (-6002 4675);
FORCEADD OFFPAGE..1
(-8300 4075);
FORCEPROP 2 LAST $XR0 47 
J 0
(-8521 4075);
DISPLAY 0.638298 (-8521 4075);
PAINT MONO (-8521 4075);
FORCEPROP 2 LAST CDS_LIB mstr_standard
J 0
(-8300 4075);
DISPLAY 0.723404 (-8300 4075);
PAINT MONO (-8300 4075);
DISPLAY INVISIBLE (-8300 4075);
FORCEPROP 1 LAST OFFPAGE TRUE
J 0
(-7975 3950);
DISPLAY 0.872340 (-7975 3950);
PAINT GREEN (-7975 3950);
DISPLAY INVISIBLE (-7975 3950);
FORCEPROP 1 LAST COMMENT_BODY TRUE
J 0
(-8175 3975);
DISPLAY 0.872340 (-8175 3975);
PAINT GREEN (-8175 3975);
DISPLAY INVISIBLE (-8175 3975);
FORCEPROP 2 LAST PATH I11
J 0
(-8500 4125);
DISPLAY 1.021277 (-8500 4125);
DISPLAY INVISIBLE (-8500 4125);
FORCEADD TAP..1
(-6000 4625);
FORCEPROP 3 LASTPIN (-6050 4625) SIG_NAME M_K_CPU1_SA_DQ<17>
J 0
(-6040 4635);
DISPLAY 0.659574 (-6040 4635);
PAINT MONO (-6040 4635);
DISPLAY INVISIBLE (-6040 4635);
FORCEPROP 1 LASTPIN (-6050 4625) BN 17
J 0
(-6062 4633);
DISPLAY 0.489362 (-6062 4633);
PAINT GREEN (-6062 4633);
FORCEPROP 2 LAST CDS_LIB mstr_standard
J 0
(-6000 4625);
DISPLAY 0.723404 (-6000 4625);
PAINT MONO (-6000 4625);
DISPLAY INVISIBLE (-6000 4625);
FORCEPROP 1 LAST BODY_TYPE PLUMBING
J 0
(-6000 4675);
DISPLAY 0.872340 (-6000 4675);
PAINT GREEN (-6000 4675);
DISPLAY INVISIBLE (-6000 4675);
FORCEPROP 1 LAST HDL_TAP TRUE
J 0
(-5675 4500);
DISPLAY 0.872340 (-5675 4500);
DISPLAY INVISIBLE (-5675 4500);
FORCEPROP 1 LAST PATH I110
J 0
(-6002 4625);
DISPLAY 0.872340 (-6002 4625);
PAINT GREEN (-6002 4625);
DISPLAY INVISIBLE (-6002 4625);
FORCEADD TAP..1
(-6000 4725);
FORCEPROP 3 LASTPIN (-6050 4725) SIG_NAME M_K_CPU1_SA_DQ<19>
J 0
(-6040 4735);
DISPLAY 0.659574 (-6040 4735);
PAINT MONO (-6040 4735);
DISPLAY INVISIBLE (-6040 4735);
FORCEPROP 1 LASTPIN (-6050 4725) BN 19
J 0
(-6062 4733);
DISPLAY 0.489362 (-6062 4733);
PAINT GREEN (-6062 4733);
FORCEPROP 2 LAST CDS_LIB mstr_standard
J 0
(-6000 4725);
DISPLAY 0.723404 (-6000 4725);
PAINT MONO (-6000 4725);
DISPLAY INVISIBLE (-6000 4725);
FORCEPROP 1 LAST BODY_TYPE PLUMBING
J 0
(-6000 4775);
DISPLAY 0.872340 (-6000 4775);
PAINT GREEN (-6000 4775);
DISPLAY INVISIBLE (-6000 4775);
FORCEPROP 1 LAST HDL_TAP TRUE
J 0
(-5675 4600);
DISPLAY 0.872340 (-5675 4600);
DISPLAY INVISIBLE (-5675 4600);
FORCEPROP 1 LAST PATH I111
J 0
(-6002 4725);
DISPLAY 0.872340 (-6002 4725);
PAINT GREEN (-6002 4725);
DISPLAY INVISIBLE (-6002 4725);
FORCEADD TAP..1
(-6000 4775);
FORCEPROP 3 LASTPIN (-6050 4775) SIG_NAME M_K_CPU1_SA_DQ<20>
J 0
(-6040 4785);
DISPLAY 0.659574 (-6040 4785);
PAINT MONO (-6040 4785);
DISPLAY INVISIBLE (-6040 4785);
FORCEPROP 1 LASTPIN (-6050 4775) BN 20
J 0
(-6062 4783);
DISPLAY 0.489362 (-6062 4783);
PAINT GREEN (-6062 4783);
FORCEPROP 2 LAST CDS_LIB mstr_standard
J 0
(-6000 4775);
DISPLAY 0.723404 (-6000 4775);
PAINT MONO (-6000 4775);
DISPLAY INVISIBLE (-6000 4775);
FORCEPROP 1 LAST BODY_TYPE PLUMBING
J 0
(-6000 4825);
DISPLAY 0.872340 (-6000 4825);
PAINT GREEN (-6000 4825);
DISPLAY INVISIBLE (-6000 4825);
FORCEPROP 1 LAST HDL_TAP TRUE
J 0
(-5675 4650);
DISPLAY 0.872340 (-5675 4650);
DISPLAY INVISIBLE (-5675 4650);
FORCEPROP 1 LAST PATH I112
J 0
(-6002 4775);
DISPLAY 0.872340 (-6002 4775);
PAINT GREEN (-6002 4775);
DISPLAY INVISIBLE (-6002 4775);
FORCEADD TAP..1
(-6000 4825);
FORCEPROP 3 LASTPIN (-6050 4825) SIG_NAME M_K_CPU1_SA_DQ<21>
J 0
(-6040 4835);
DISPLAY 0.659574 (-6040 4835);
PAINT MONO (-6040 4835);
DISPLAY INVISIBLE (-6040 4835);
FORCEPROP 1 LASTPIN (-6050 4825) BN 21
J 0
(-6062 4833);
DISPLAY 0.489362 (-6062 4833);
PAINT GREEN (-6062 4833);
FORCEPROP 2 LAST CDS_LIB mstr_standard
J 0
(-6000 4825);
DISPLAY 0.723404 (-6000 4825);
PAINT MONO (-6000 4825);
DISPLAY INVISIBLE (-6000 4825);
FORCEPROP 1 LAST BODY_TYPE PLUMBING
J 0
(-6000 4875);
DISPLAY 0.872340 (-6000 4875);
PAINT GREEN (-6000 4875);
DISPLAY INVISIBLE (-6000 4875);
FORCEPROP 1 LAST HDL_TAP TRUE
J 0
(-5675 4700);
DISPLAY 0.872340 (-5675 4700);
DISPLAY INVISIBLE (-5675 4700);
FORCEPROP 1 LAST PATH I113
J 0
(-6002 4825);
DISPLAY 0.872340 (-6002 4825);
PAINT GREEN (-6002 4825);
DISPLAY INVISIBLE (-6002 4825);
FORCEADD TAP..1
(-6000 4875);
FORCEPROP 3 LASTPIN (-6050 4875) SIG_NAME M_K_CPU1_SA_DQ<22>
J 0
(-6040 4885);
DISPLAY 0.659574 (-6040 4885);
PAINT MONO (-6040 4885);
DISPLAY INVISIBLE (-6040 4885);
FORCEPROP 1 LASTPIN (-6050 4875) BN 22
J 0
(-6062 4883);
DISPLAY 0.489362 (-6062 4883);
PAINT GREEN (-6062 4883);
FORCEPROP 2 LAST CDS_LIB mstr_standard
J 0
(-6000 4875);
DISPLAY 0.723404 (-6000 4875);
PAINT MONO (-6000 4875);
DISPLAY INVISIBLE (-6000 4875);
FORCEPROP 1 LAST BODY_TYPE PLUMBING
J 0
(-6000 4925);
DISPLAY 0.872340 (-6000 4925);
PAINT GREEN (-6000 4925);
DISPLAY INVISIBLE (-6000 4925);
FORCEPROP 1 LAST HDL_TAP TRUE
J 0
(-5675 4750);
DISPLAY 0.872340 (-5675 4750);
DISPLAY INVISIBLE (-5675 4750);
FORCEPROP 1 LAST PATH I114
J 0
(-6002 4875);
DISPLAY 0.872340 (-6002 4875);
PAINT GREEN (-6002 4875);
DISPLAY INVISIBLE (-6002 4875);
FORCEADD TAP..1
(-6000 4925);
FORCEPROP 3 LASTPIN (-6050 4925) SIG_NAME M_K_CPU1_SA_DQ<23>
J 0
(-6040 4935);
DISPLAY 0.659574 (-6040 4935);
PAINT MONO (-6040 4935);
DISPLAY INVISIBLE (-6040 4935);
FORCEPROP 1 LASTPIN (-6050 4925) BN 23
J 0
(-6062 4933);
DISPLAY 0.489362 (-6062 4933);
PAINT GREEN (-6062 4933);
FORCEPROP 2 LAST CDS_LIB mstr_standard
J 0
(-6000 4925);
DISPLAY 0.723404 (-6000 4925);
PAINT MONO (-6000 4925);
DISPLAY INVISIBLE (-6000 4925);
FORCEPROP 1 LAST BODY_TYPE PLUMBING
J 0
(-6000 4975);
DISPLAY 0.872340 (-6000 4975);
PAINT GREEN (-6000 4975);
DISPLAY INVISIBLE (-6000 4975);
FORCEPROP 1 LAST HDL_TAP TRUE
J 0
(-5675 4800);
DISPLAY 0.872340 (-5675 4800);
DISPLAY INVISIBLE (-5675 4800);
FORCEPROP 1 LAST PATH I115
J 0
(-6002 4925);
DISPLAY 0.872340 (-6002 4925);
PAINT GREEN (-6002 4925);
DISPLAY INVISIBLE (-6002 4925);
FORCEADD TAP..1
(-6000 4975);
FORCEPROP 3 LASTPIN (-6050 4975) SIG_NAME M_K_CPU1_SA_DQ<24>
J 0
(-6040 4985);
DISPLAY 0.659574 (-6040 4985);
PAINT MONO (-6040 4985);
DISPLAY INVISIBLE (-6040 4985);
FORCEPROP 1 LASTPIN (-6050 4975) BN 24
J 0
(-6062 4983);
DISPLAY 0.489362 (-6062 4983);
PAINT GREEN (-6062 4983);
FORCEPROP 2 LAST CDS_LIB mstr_standard
J 0
(-6000 4975);
DISPLAY 0.723404 (-6000 4975);
PAINT MONO (-6000 4975);
DISPLAY INVISIBLE (-6000 4975);
FORCEPROP 1 LAST BODY_TYPE PLUMBING
J 0
(-6000 5025);
DISPLAY 0.872340 (-6000 5025);
PAINT GREEN (-6000 5025);
DISPLAY INVISIBLE (-6000 5025);
FORCEPROP 1 LAST HDL_TAP TRUE
J 0
(-5675 4850);
DISPLAY 0.872340 (-5675 4850);
DISPLAY INVISIBLE (-5675 4850);
FORCEPROP 1 LAST PATH I116
J 0
(-6002 4975);
DISPLAY 0.872340 (-6002 4975);
PAINT GREEN (-6002 4975);
DISPLAY INVISIBLE (-6002 4975);
FORCEADD TAP..1
(-6000 5025);
FORCEPROP 3 LASTPIN (-6050 5025) SIG_NAME M_K_CPU1_SA_DQ<25>
J 0
(-6040 5035);
DISPLAY 0.659574 (-6040 5035);
PAINT MONO (-6040 5035);
DISPLAY INVISIBLE (-6040 5035);
FORCEPROP 1 LASTPIN (-6050 5025) BN 25
J 0
(-6062 5033);
DISPLAY 0.489362 (-6062 5033);
PAINT GREEN (-6062 5033);
FORCEPROP 2 LAST CDS_LIB mstr_standard
J 0
(-6000 5025);
DISPLAY 0.723404 (-6000 5025);
PAINT MONO (-6000 5025);
DISPLAY INVISIBLE (-6000 5025);
FORCEPROP 1 LAST BODY_TYPE PLUMBING
J 0
(-6000 5075);
DISPLAY 0.872340 (-6000 5075);
PAINT GREEN (-6000 5075);
DISPLAY INVISIBLE (-6000 5075);
FORCEPROP 1 LAST HDL_TAP TRUE
J 0
(-5675 4900);
DISPLAY 0.872340 (-5675 4900);
DISPLAY INVISIBLE (-5675 4900);
FORCEPROP 1 LAST PATH I117
J 0
(-6002 5025);
DISPLAY 0.872340 (-6002 5025);
PAINT GREEN (-6002 5025);
DISPLAY INVISIBLE (-6002 5025);
FORCEADD TAP..1
(-6000 5075);
FORCEPROP 3 LASTPIN (-6050 5075) SIG_NAME M_K_CPU1_SA_DQ<26>
J 0
(-6040 5085);
DISPLAY 0.659574 (-6040 5085);
PAINT MONO (-6040 5085);
DISPLAY INVISIBLE (-6040 5085);
FORCEPROP 1 LASTPIN (-6050 5075) BN 26
J 0
(-6062 5083);
DISPLAY 0.489362 (-6062 5083);
PAINT GREEN (-6062 5083);
FORCEPROP 2 LAST CDS_LIB mstr_standard
J 0
(-6000 5075);
DISPLAY 0.723404 (-6000 5075);
PAINT MONO (-6000 5075);
DISPLAY INVISIBLE (-6000 5075);
FORCEPROP 1 LAST BODY_TYPE PLUMBING
J 0
(-6000 5125);
DISPLAY 0.872340 (-6000 5125);
PAINT GREEN (-6000 5125);
DISPLAY INVISIBLE (-6000 5125);
FORCEPROP 1 LAST HDL_TAP TRUE
J 0
(-5675 4950);
DISPLAY 0.872340 (-5675 4950);
DISPLAY INVISIBLE (-5675 4950);
FORCEPROP 1 LAST PATH I118
J 0
(-6002 5075);
DISPLAY 0.872340 (-6002 5075);
PAINT GREEN (-6002 5075);
DISPLAY INVISIBLE (-6002 5075);
FORCEADD TAP..1
(-6000 5125);
FORCEPROP 3 LASTPIN (-6050 5125) SIG_NAME M_K_CPU1_SA_DQ<27>
J 0
(-6040 5135);
DISPLAY 0.659574 (-6040 5135);
PAINT MONO (-6040 5135);
DISPLAY INVISIBLE (-6040 5135);
FORCEPROP 1 LASTPIN (-6050 5125) BN 27
J 0
(-6062 5133);
DISPLAY 0.489362 (-6062 5133);
PAINT GREEN (-6062 5133);
FORCEPROP 2 LAST CDS_LIB mstr_standard
J 0
(-6000 5125);
DISPLAY 0.723404 (-6000 5125);
PAINT MONO (-6000 5125);
DISPLAY INVISIBLE (-6000 5125);
FORCEPROP 1 LAST BODY_TYPE PLUMBING
J 0
(-6000 5175);
DISPLAY 0.872340 (-6000 5175);
PAINT GREEN (-6000 5175);
DISPLAY INVISIBLE (-6000 5175);
FORCEPROP 1 LAST HDL_TAP TRUE
J 0
(-5675 5000);
DISPLAY 0.872340 (-5675 5000);
DISPLAY INVISIBLE (-5675 5000);
FORCEPROP 1 LAST PATH I119
J 0
(-6002 5125);
DISPLAY 0.872340 (-6002 5125);
PAINT GREEN (-6002 5125);
DISPLAY INVISIBLE (-6002 5125);
FORCEADD OFFPAGE..1
(-8300 4025);
FORCEPROP 2 LAST $XR0 47 
J 0
(-8521 4025);
DISPLAY 0.638298 (-8521 4025);
PAINT MONO (-8521 4025);
FORCEPROP 2 LAST CDS_LIB mstr_standard
J 0
(-8300 4025);
DISPLAY 0.808511 (-8300 4025);
DISPLAY INVISIBLE (-8300 4025);
FORCEPROP 1 LAST OFFPAGE TRUE
J 0
(-7975 3900);
DISPLAY 0.872340 (-7975 3900);
PAINT GREEN (-7975 3900);
DISPLAY INVISIBLE (-7975 3900);
FORCEPROP 1 LAST COMMENT_BODY TRUE
J 0
(-8175 3925);
DISPLAY 0.872340 (-8175 3925);
PAINT GREEN (-8175 3925);
DISPLAY INVISIBLE (-8175 3925);
FORCEPROP 2 LAST PATH I12
J 0
(-8500 4075);
DISPLAY 1.021277 (-8500 4075);
DISPLAY INVISIBLE (-8500 4075);
FORCEADD TAP..1
(-6000 5175);
FORCEPROP 3 LASTPIN (-6050 5175) SIG_NAME M_K_CPU1_SA_DQ<28>
J 0
(-6040 5185);
DISPLAY 0.659574 (-6040 5185);
PAINT MONO (-6040 5185);
DISPLAY INVISIBLE (-6040 5185);
FORCEPROP 1 LASTPIN (-6050 5175) BN 28
J 0
(-6062 5183);
DISPLAY 0.489362 (-6062 5183);
PAINT GREEN (-6062 5183);
FORCEPROP 2 LAST CDS_LIB mstr_standard
J 0
(-6000 5175);
DISPLAY 0.723404 (-6000 5175);
PAINT MONO (-6000 5175);
DISPLAY INVISIBLE (-6000 5175);
FORCEPROP 1 LAST BODY_TYPE PLUMBING
J 0
(-6000 5225);
DISPLAY 0.872340 (-6000 5225);
PAINT GREEN (-6000 5225);
DISPLAY INVISIBLE (-6000 5225);
FORCEPROP 1 LAST HDL_TAP TRUE
J 0
(-5675 5050);
DISPLAY 0.872340 (-5675 5050);
DISPLAY INVISIBLE (-5675 5050);
FORCEPROP 1 LAST PATH I120
J 0
(-6002 5175);
DISPLAY 0.872340 (-6002 5175);
PAINT GREEN (-6002 5175);
DISPLAY INVISIBLE (-6002 5175);
FORCEADD TAP..1
(-6000 5275);
FORCEPROP 3 LASTPIN (-6050 5275) SIG_NAME M_K_CPU1_SA_DQ<30>
J 0
(-6040 5285);
DISPLAY 0.659574 (-6040 5285);
PAINT MONO (-6040 5285);
DISPLAY INVISIBLE (-6040 5285);
FORCEPROP 1 LASTPIN (-6050 5275) BN 30
J 0
(-6062 5283);
DISPLAY 0.489362 (-6062 5283);
PAINT GREEN (-6062 5283);
FORCEPROP 2 LAST CDS_LIB mstr_standard
J 0
(-6000 5275);
DISPLAY 0.723404 (-6000 5275);
PAINT MONO (-6000 5275);
DISPLAY INVISIBLE (-6000 5275);
FORCEPROP 1 LAST BODY_TYPE PLUMBING
J 0
(-6000 5325);
DISPLAY 0.872340 (-6000 5325);
PAINT GREEN (-6000 5325);
DISPLAY INVISIBLE (-6000 5325);
FORCEPROP 1 LAST HDL_TAP TRUE
J 0
(-5675 5150);
DISPLAY 0.872340 (-5675 5150);
DISPLAY INVISIBLE (-5675 5150);
FORCEPROP 1 LAST PATH I121
J 0
(-6002 5275);
DISPLAY 0.872340 (-6002 5275);
PAINT GREEN (-6002 5275);
DISPLAY INVISIBLE (-6002 5275);
FORCEADD TAP..1
(-6000 5325);
FORCEPROP 3 LASTPIN (-6050 5325) SIG_NAME M_K_CPU1_SA_DQ<31>
J 0
(-6040 5335);
DISPLAY 0.659574 (-6040 5335);
PAINT MONO (-6040 5335);
DISPLAY INVISIBLE (-6040 5335);
FORCEPROP 1 LASTPIN (-6050 5325) BN 31
J 0
(-6062 5333);
DISPLAY 0.489362 (-6062 5333);
PAINT GREEN (-6062 5333);
FORCEPROP 2 LAST CDS_LIB mstr_standard
J 0
(-6000 5325);
DISPLAY 0.723404 (-6000 5325);
PAINT MONO (-6000 5325);
DISPLAY INVISIBLE (-6000 5325);
FORCEPROP 1 LAST BODY_TYPE PLUMBING
J 0
(-6000 5375);
DISPLAY 0.872340 (-6000 5375);
PAINT GREEN (-6000 5375);
DISPLAY INVISIBLE (-6000 5375);
FORCEPROP 1 LAST HDL_TAP TRUE
J 0
(-5675 5200);
DISPLAY 0.872340 (-5675 5200);
DISPLAY INVISIBLE (-5675 5200);
FORCEPROP 1 LAST PATH I122
J 0
(-6002 5325);
DISPLAY 0.872340 (-6002 5325);
PAINT GREEN (-6002 5325);
DISPLAY INVISIBLE (-6002 5325);
FORCEADD TAP..1
(-6000 5225);
FORCEPROP 3 LASTPIN (-6050 5225) SIG_NAME M_K_CPU1_SA_DQ<29>
J 0
(-6040 5235);
DISPLAY 0.659574 (-6040 5235);
PAINT MONO (-6040 5235);
DISPLAY INVISIBLE (-6040 5235);
FORCEPROP 1 LASTPIN (-6050 5225) BN 29
J 0
(-6062 5233);
DISPLAY 0.489362 (-6062 5233);
PAINT GREEN (-6062 5233);
FORCEPROP 2 LAST CDS_LIB mstr_standard
J 0
(-6000 5225);
DISPLAY 0.723404 (-6000 5225);
PAINT MONO (-6000 5225);
DISPLAY INVISIBLE (-6000 5225);
FORCEPROP 1 LAST BODY_TYPE PLUMBING
J 0
(-6000 5275);
DISPLAY 0.872340 (-6000 5275);
PAINT GREEN (-6000 5275);
DISPLAY INVISIBLE (-6000 5275);
FORCEPROP 1 LAST HDL_TAP TRUE
J 0
(-5675 5100);
DISPLAY 0.872340 (-5675 5100);
DISPLAY INVISIBLE (-5675 5100);
FORCEPROP 1 LAST PATH I123
J 0
(-6002 5225);
DISPLAY 0.872340 (-6002 5225);
PAINT GREEN (-6002 5225);
DISPLAY INVISIBLE (-6002 5225);
FORCEADD OFFPAGE..3
(-5325 3725);
FORCEPROP 2 LAST $XR0 47 
J 0
(-5111 3725);
DISPLAY 0.638298 (-5111 3725);
PAINT MONO (-5111 3725);
FORCEPROP 2 LAST CDS_LIB mstr_standard
J 0
(-5325 3725);
DISPLAY 0.723404 (-5325 3725);
PAINT MONO (-5325 3725);
DISPLAY INVISIBLE (-5325 3725);
FORCEPROP 1 LAST OFFPAGE TRUE
J 0
(-5000 3600);
DISPLAY 0.872340 (-5000 3600);
PAINT GREEN (-5000 3600);
DISPLAY INVISIBLE (-5000 3600);
FORCEPROP 1 LAST COMMENT_BODY TRUE
J 0
(-5375 3625);
DISPLAY 0.872340 (-5375 3625);
PAINT GREEN (-5375 3625);
DISPLAY INVISIBLE (-5375 3625);
FORCEPROP 2 LAST PATH I124
J 0
(-5100 3775);
DISPLAY 1.021277 (-5100 3775);
DISPLAY INVISIBLE (-5100 3775);
FORCEADD OFFPAGE..3
(-5325 5375);
FORCEPROP 2 LAST $XR0 47 
J 0
(-5111 5375);
DISPLAY 0.638298 (-5111 5375);
PAINT MONO (-5111 5375);
FORCEPROP 2 LAST CDS_LIB mstr_standard
J 0
(-5325 5375);
DISPLAY 0.723404 (-5325 5375);
PAINT MONO (-5325 5375);
DISPLAY INVISIBLE (-5325 5375);
FORCEPROP 1 LAST OFFPAGE TRUE
J 0
(-5000 5250);
DISPLAY 0.872340 (-5000 5250);
PAINT GREEN (-5000 5250);
DISPLAY INVISIBLE (-5000 5250);
FORCEPROP 1 LAST COMMENT_BODY TRUE
J 0
(-5375 5275);
DISPLAY 0.872340 (-5375 5275);
PAINT GREEN (-5375 5275);
DISPLAY INVISIBLE (-5375 5275);
FORCEPROP 2 LAST PATH I125
J 0
(-5100 5425);
DISPLAY 1.021277 (-5100 5425);
DISPLAY INVISIBLE (-5100 5425);
FORCEADD GND..1
(-6400 875);
FORCEPROP 3 LASTPIN (-6400 925) SIG_NAME GND\g
J 0
(-6390 935);
DISPLAY 0.659574 (-6390 935);
PAINT MONO (-6390 935);
DISPLAY INVISIBLE (-6390 935);
FORCEPROP 2 LAST BOM_COST MEM
J 0
(-6500 950);
DISPLAY 0.808511 (-6500 950);
DISPLAY INVISIBLE (-6500 950);
FORCEPROP 1 LAST SIZE 1B
J 0
(-6325 825);
DISPLAY 0.851064 (-6325 825);
PAINT GREEN (-6325 825);
DISPLAY INVISIBLE (-6325 825);
FORCEPROP 2 LAST CDS_LIB mstr_symbols
J 0
(-6400 875);
DISPLAY 0.808511 (-6400 875);
DISPLAY INVISIBLE (-6400 875);
FORCEPROP 1 LAST BODY_TYPE PLUMBING
J 0
(-6445 832);
DISPLAY 0.340426 (-6445 832);
PAINT GREEN (-6445 832);
DISPLAY INVISIBLE (-6445 832);
FORCEPROP 1 LAST PATH I126
J 0
(-6325 875);
DISPLAY 0.872340 (-6325 875);
PAINT AQUA (-6325 875);
DISPLAY INVISIBLE (-6325 875);
FORCEPROP 1 LAST VOLTAGE 0.0
J 0
(-6445 832);
DISPLAY 0.723404 (-6445 832);
PAINT SKYBLUE (-6445 832);
DISPLAY INVISIBLE (-6445 832);
FORCEPROP 1 LAST HDL_POWER GND
J 0
(-6400 1025);
DISPLAY 0.851064 (-6400 1025);
PAINT GREEN (-6400 1025);
DISPLAY INVISIBLE (-6400 1025);
FORCEADD OFFPAGE..5
(-7175 1275);
FORCEPROP 2 LAST $XR0 107 
J 0
(-7460 1275);
DISPLAY 0.638298 (-7460 1275);
PAINT MONO (-7460 1275);
FORCEPROP 2 LAST CDS_LIB mstr_standard
J 0
(-7175 1275);
DISPLAY 0.808511 (-7175 1275);
DISPLAY INVISIBLE (-7175 1275);
FORCEPROP 2 LAST BOM_COST MEM
J 0
(-7250 1350);
DISPLAY 0.808511 (-7250 1350);
DISPLAY INVISIBLE (-7250 1350);
FORCEPROP 1 LAST OFFPAGE TRUE
J 0
(-6850 1150);
DISPLAY 0.872340 (-6850 1150);
PAINT GREEN (-6850 1150);
DISPLAY INVISIBLE (-6850 1150);
FORCEPROP 1 LAST COMMENT_BODY TRUE
J 0
(-7075 1200);
DISPLAY 0.872340 (-7075 1200);
PAINT GREEN (-7075 1200);
DISPLAY INVISIBLE (-7075 1200);
FORCEPROP 2 LAST PATH I127
J 0
(-7450 1325);
DISPLAY 1.021277 (-7450 1325);
DISPLAY INVISIBLE (-7450 1325);
FORCEADD OFFPAGE..6
(-8300 3975);
FORCEPROP 2 LAST $XR0 47 
J 0
(-8549 3975);
DISPLAY 0.638298 (-8549 3975);
PAINT MONO (-8549 3975);
FORCEPROP 2 LAST CDS_LIB mstr_standard
J 0
(-8300 3975);
DISPLAY 0.723404 (-8300 3975);
PAINT MONO (-8300 3975);
DISPLAY INVISIBLE (-8300 3975);
FORCEPROP 1 LAST OFFPAGE TRUE
J 0
(-7975 3850);
DISPLAY 0.872340 (-7975 3850);
PAINT GREEN (-7975 3850);
DISPLAY INVISIBLE (-7975 3850);
FORCEPROP 1 LAST COMMENT_BODY TRUE
J 0
(-8200 3900);
DISPLAY 0.872340 (-8200 3900);
PAINT GREEN (-8200 3900);
DISPLAY INVISIBLE (-8200 3900);
FORCEPROP 2 LAST PATH I13
J 0
(-8575 4025);
DISPLAY 1.021277 (-8575 4025);
DISPLAY INVISIBLE (-8575 4025);
FORCEADD Q_RES..2
(-6400 1100);
FORCEPROP 1 LAST LOCATION R777
J 0
(-6355 1225);
DISPLAY 0.489362 (-6355 1225);
PAINT SKYBLUE (-6355 1225);
FORCEPROP 0 LAST $SEC 1
J 0
(-6350 1275);
DISPLAY 0.680851 (-6350 1275);
PAINT MONO (-6350 1275);
DISPLAY INVISIBLE (-6350 1275);
FORCEPROP 0 LAST CDS_SEC 1
J 0
(-6350 1275);
DISPLAY 1.021277 (-6350 1275);
DISPLAY INVISIBLE (-6350 1275);
FORCEPROP 1 LASTPIN (-6400 1200) $PN 1
J 0
(-6395 1162);
DISPLAY 0.489362 (-6395 1162);
PAINT MONO (-6395 1162);
FORCEPROP 1 LASTPIN (-6400 1000) $PN 2
J 0
(-6395 1010);
DISPLAY 0.489362 (-6395 1010);
PAINT MONO (-6395 1010);
FORCEPROP 1 LAST WATTAGE 1/16W
J 0
(-6360 1075);
DISPLAY 0.489362 (-6360 1075);
PAINT SKYBLUE (-6360 1075);
FORCEPROP 1 LAST MATERIAL CHIP
J 0
(-6360 1025);
DISPLAY 0.489362 (-6360 1025);
PAINT SKYBLUE (-6360 1025);
FORCEPROP 1 LAST TOLERANCE 1%
J 0
(-6355 1125);
DISPLAY 0.489362 (-6355 1125);
PAINT SKYBLUE (-6355 1125);
FORCEPROP 1 LAST VALUE 54.9K
J 0
(-6355 1175);
DISPLAY 0.489362 (-6355 1175);
PAINT SKYBLUE (-6355 1175);
FORCEPROP 1 LAST PART_NUMBER TMP_QCS35492FB14
J 0
(-6360 975);
DISPLAY 0.489362 (-6360 975);
PAINT SKYBLUE (-6360 975);
FORCEPROP 1 LAST PACK_TYPE 0402LF
J 0
(-6360 925);
DISPLAY 0.489362 (-6360 925);
PAINT SKYBLUE (-6360 925);
FORCEPROP 2 LAST CDS_LIB pure_quanta
J 0
(-6400 1100);
DISPLAY INVISIBLE (-6400 1100);
FORCEPROP 1 LAST PATH I136
J 0
(-6350 1275);
DISPLAY 0.978723 (-6350 1275);
PAINT WHITE (-6350 1275);
DISPLAY INVISIBLE (-6350 1275);
FORCEADD GND..1
(-2150 1850);
FORCEPROP 3 LASTPIN (-2150 1900) SIG_NAME GND\g
J 0
(-2140 1910);
DISPLAY 0.659574 (-2140 1910);
PAINT MONO (-2140 1910);
DISPLAY INVISIBLE (-2140 1910);
FORCEPROP 2 LAST CDS_LIB mstr_symbols
J 0
(-2150 1850);
DISPLAY 0.723404 (-2150 1850);
DISPLAY INVISIBLE (-2150 1850);
FORCEPROP 1 LAST SIZE 1B
J 0
(-2075 1800);
DISPLAY 0.851064 (-2075 1800);
PAINT GREEN (-2075 1800);
DISPLAY INVISIBLE (-2075 1800);
FORCEPROP 1 LAST BODY_TYPE PLUMBING
J 0
(-2195 1807);
DISPLAY 0.340426 (-2195 1807);
PAINT GREEN (-2195 1807);
DISPLAY INVISIBLE (-2195 1807);
FORCEPROP 1 LAST PATH I137
J 0
(-2075 1850);
DISPLAY 0.872340 (-2075 1850);
PAINT AQUA (-2075 1850);
DISPLAY INVISIBLE (-2075 1850);
FORCEPROP 1 LAST VOLTAGE 0.0
J 0
(-2195 1807);
DISPLAY 0.723404 (-2195 1807);
PAINT SKYBLUE (-2195 1807);
DISPLAY INVISIBLE (-2195 1807);
FORCEPROP 1 LAST HDL_POWER GND
J 0
(-2150 2000);
DISPLAY 0.851064 (-2150 2000);
PAINT GREEN (-2150 2000);
DISPLAY INVISIBLE (-2150 2000);
FORCEADD GND..1
(-350 1625);
FORCEPROP 3 LASTPIN (-350 1675) SIG_NAME GND\g
J 0
(-340 1685);
DISPLAY 0.659574 (-340 1685);
PAINT MONO (-340 1685);
DISPLAY INVISIBLE (-340 1685);
FORCEPROP 2 LAST CDS_LIB mstr_symbols
J 0
(-350 1625);
DISPLAY 0.723404 (-350 1625);
DISPLAY INVISIBLE (-350 1625);
FORCEPROP 1 LAST SIZE 1B
J 0
(-275 1575);
DISPLAY 0.851064 (-275 1575);
PAINT GREEN (-275 1575);
DISPLAY INVISIBLE (-275 1575);
FORCEPROP 1 LAST BODY_TYPE PLUMBING
J 0
(-395 1582);
DISPLAY 0.340426 (-395 1582);
PAINT GREEN (-395 1582);
DISPLAY INVISIBLE (-395 1582);
FORCEPROP 1 LAST PATH I138
J 0
(-275 1625);
DISPLAY 0.872340 (-275 1625);
PAINT AQUA (-275 1625);
DISPLAY INVISIBLE (-275 1625);
FORCEPROP 1 LAST VOLTAGE 0.0
J 0
(-395 1582);
DISPLAY 0.723404 (-395 1582);
PAINT SKYBLUE (-395 1582);
DISPLAY INVISIBLE (-395 1582);
FORCEPROP 1 LAST HDL_POWER GND
J 0
(-350 1775);
DISPLAY 0.851064 (-350 1775);
PAINT GREEN (-350 1775);
DISPLAY INVISIBLE (-350 1775);
FORCEADD SCONN288_DDR506112002KQ..3
(-1250 3625);
FORCEPROP 1 LAST LOCATION J99
J 0
(-1700 5600);
DISPLAY 0.468085 (-1700 5600);
PAINT SKYBLUE (-1700 5600);
FORCEPROP 0 LAST $SEC 3
J 0
(-1700 5750);
DISPLAY 0.680851 (-1700 5750);
PAINT MONO (-1700 5750);
DISPLAY INVISIBLE (-1700 5750);
FORCEPROP 2 LAST CDS_SEC 3
J 0
(-1700 5750);
DISPLAY 1.021277 (-1700 5750);
DISPLAY INVISIBLE (-1700 5750);
FORCEPROP 0 LASTPIN (-650 2025) $PN G1
J 0
(-640 2035);
DISPLAY 0.680851 (-640 2035);
PAINT MONO (-640 2035);
FORCEPROP 0 LASTPIN (-650 1975) $PN G2
J 0
(-640 1985);
DISPLAY 0.680851 (-640 1985);
PAINT MONO (-640 1985);
FORCEPROP 0 LASTPIN (-650 1925) $PN G3
J 0
(-640 1935);
DISPLAY 0.680851 (-640 1935);
PAINT MONO (-640 1935);
FORCEPROP 0 LASTPIN (-1850 5175) $PN 1
J 2
(-1860 5185);
DISPLAY 0.680851 (-1860 5185);
PAINT MONO (-1860 5185);
FORCEPROP 0 LASTPIN (-1850 5225) $PN 145
J 2
(-1860 5235);
DISPLAY 0.680851 (-1860 5235);
PAINT MONO (-1860 5235);
FORCEPROP 0 LASTPIN (-1850 5275) $PN 146
J 2
(-1860 5285);
DISPLAY 0.680851 (-1860 5285);
PAINT MONO (-1860 5285);
FORCEPROP 0 LASTPIN (-650 2125) $PN 6
J 0
(-640 2135);
DISPLAY 0.680851 (-640 2135);
PAINT MONO (-640 2135);
FORCEPROP 0 LASTPIN (-650 2175) $PN 8
J 0
(-640 2185);
DISPLAY 0.680851 (-640 2185);
PAINT MONO (-640 2185);
FORCEPROP 0 LASTPIN (-650 2225) $PN 10
J 0
(-640 2235);
DISPLAY 0.680851 (-640 2235);
PAINT MONO (-640 2235);
FORCEPROP 0 LASTPIN (-650 2275) $PN 13
J 0
(-640 2285);
DISPLAY 0.680851 (-640 2285);
PAINT MONO (-640 2285);
FORCEPROP 0 LASTPIN (-650 2325) $PN 15
J 0
(-640 2335);
DISPLAY 0.680851 (-640 2335);
PAINT MONO (-640 2335);
FORCEPROP 0 LASTPIN (-650 2375) $PN 17
J 0
(-640 2385);
DISPLAY 0.680851 (-640 2385);
PAINT MONO (-640 2385);
FORCEPROP 0 LASTPIN (-650 2425) $PN 19
J 0
(-640 2435);
DISPLAY 0.680851 (-640 2435);
PAINT MONO (-640 2435);
FORCEPROP 0 LASTPIN (-650 2475) $PN 21
J 0
(-640 2485);
DISPLAY 0.680851 (-640 2485);
PAINT MONO (-640 2485);
FORCEPROP 0 LASTPIN (-650 2525) $PN 24
J 0
(-640 2535);
DISPLAY 0.680851 (-640 2535);
PAINT MONO (-640 2535);
FORCEPROP 0 LASTPIN (-650 2575) $PN 26
J 0
(-640 2585);
DISPLAY 0.680851 (-640 2585);
PAINT MONO (-640 2585);
FORCEPROP 0 LASTPIN (-650 2625) $PN 28
J 0
(-640 2635);
DISPLAY 0.680851 (-640 2635);
PAINT MONO (-640 2635);
FORCEPROP 0 LASTPIN (-650 2675) $PN 30
J 0
(-640 2685);
DISPLAY 0.680851 (-640 2685);
PAINT MONO (-640 2685);
FORCEPROP 0 LASTPIN (-650 2725) $PN 32
J 0
(-640 2735);
DISPLAY 0.680851 (-640 2735);
PAINT MONO (-640 2735);
FORCEPROP 0 LASTPIN (-650 2775) $PN 35
J 0
(-640 2785);
DISPLAY 0.680851 (-640 2785);
PAINT MONO (-640 2785);
FORCEPROP 0 LASTPIN (-650 2825) $PN 37
J 0
(-640 2835);
DISPLAY 0.680851 (-640 2835);
PAINT MONO (-640 2835);
FORCEPROP 0 LASTPIN (-650 2875) $PN 39
J 0
(-640 2885);
DISPLAY 0.680851 (-640 2885);
PAINT MONO (-640 2885);
FORCEPROP 0 LASTPIN (-650 2925) $PN 41
J 0
(-640 2935);
DISPLAY 0.680851 (-640 2935);
PAINT MONO (-640 2935);
FORCEPROP 0 LASTPIN (-650 2975) $PN 43
J 0
(-640 2985);
DISPLAY 0.680851 (-640 2985);
PAINT MONO (-640 2985);
FORCEPROP 0 LASTPIN (-650 3025) $PN 46
J 0
(-640 3035);
DISPLAY 0.680851 (-640 3035);
PAINT MONO (-640 3035);
FORCEPROP 0 LASTPIN (-650 3075) $PN 48
J 0
(-640 3085);
DISPLAY 0.680851 (-640 3085);
PAINT MONO (-640 3085);
FORCEPROP 0 LASTPIN (-650 3125) $PN 50
J 0
(-640 3135);
DISPLAY 0.680851 (-640 3135);
PAINT MONO (-640 3135);
FORCEPROP 0 LASTPIN (-650 3175) $PN 52
J 0
(-640 3185);
DISPLAY 0.680851 (-640 3185);
PAINT MONO (-640 3185);
FORCEPROP 0 LASTPIN (-650 3225) $PN 54
J 0
(-640 3235);
DISPLAY 0.680851 (-640 3235);
PAINT MONO (-640 3235);
FORCEPROP 0 LASTPIN (-650 3275) $PN 57
J 0
(-640 3285);
DISPLAY 0.680851 (-640 3285);
PAINT MONO (-640 3285);
FORCEPROP 0 LASTPIN (-650 3325) $PN 59
J 0
(-640 3335);
DISPLAY 0.680851 (-640 3335);
PAINT MONO (-640 3335);
FORCEPROP 0 LASTPIN (-650 3375) $PN 61
J 0
(-640 3385);
DISPLAY 0.680851 (-640 3385);
PAINT MONO (-640 3385);
FORCEPROP 0 LASTPIN (-650 3425) $PN 63
J 0
(-640 3435);
DISPLAY 0.680851 (-640 3435);
PAINT MONO (-640 3435);
FORCEPROP 0 LASTPIN (-650 3475) $PN 65
J 0
(-640 3485);
DISPLAY 0.680851 (-640 3485);
PAINT MONO (-640 3485);
FORCEPROP 0 LASTPIN (-650 3525) $PN 67
J 0
(-640 3535);
DISPLAY 0.680851 (-640 3535);
PAINT MONO (-640 3535);
FORCEPROP 0 LASTPIN (-650 3575) $PN 69
J 0
(-640 3585);
DISPLAY 0.680851 (-640 3585);
PAINT MONO (-640 3585);
FORCEPROP 0 LASTPIN (-650 3625) $PN 71
J 0
(-640 3635);
DISPLAY 0.680851 (-640 3635);
PAINT MONO (-640 3635);
FORCEPROP 0 LASTPIN (-650 3675) $PN 73
J 0
(-640 3685);
DISPLAY 0.680851 (-640 3685);
PAINT MONO (-640 3685);
FORCEPROP 0 LASTPIN (-650 3725) $PN 75
J 0
(-640 3735);
DISPLAY 0.680851 (-640 3735);
PAINT MONO (-640 3735);
FORCEPROP 0 LASTPIN (-650 3775) $PN 77
J 0
(-640 3785);
DISPLAY 0.680851 (-640 3785);
PAINT MONO (-640 3785);
FORCEPROP 0 LASTPIN (-650 3825) $PN 79
J 0
(-640 3835);
DISPLAY 0.680851 (-640 3835);
PAINT MONO (-640 3835);
FORCEPROP 0 LASTPIN (-650 3875) $PN 81
J 0
(-640 3885);
DISPLAY 0.680851 (-640 3885);
PAINT MONO (-640 3885);
FORCEPROP 0 LASTPIN (-650 3925) $PN 83
J 0
(-640 3935);
DISPLAY 0.680851 (-640 3935);
PAINT MONO (-640 3935);
FORCEPROP 0 LASTPIN (-650 3975) $PN 85
J 0
(-640 3985);
DISPLAY 0.680851 (-640 3985);
PAINT MONO (-640 3985);
FORCEPROP 0 LASTPIN (-650 4025) $PN 88
J 0
(-640 4035);
DISPLAY 0.680851 (-640 4035);
PAINT MONO (-640 4035);
FORCEPROP 0 LASTPIN (-650 4075) $PN 90
J 0
(-640 4085);
DISPLAY 0.680851 (-640 4085);
PAINT MONO (-640 4085);
FORCEPROP 0 LASTPIN (-650 4125) $PN 92
J 0
(-640 4135);
DISPLAY 0.680851 (-640 4135);
PAINT MONO (-640 4135);
FORCEPROP 0 LASTPIN (-650 4175) $PN 95
J 0
(-640 4185);
DISPLAY 0.680851 (-640 4185);
PAINT MONO (-640 4185);
FORCEPROP 0 LASTPIN (-650 4225) $PN 97
J 0
(-640 4235);
DISPLAY 0.680851 (-640 4235);
PAINT MONO (-640 4235);
FORCEPROP 0 LASTPIN (-650 4275) $PN 99
J 0
(-640 4285);
DISPLAY 0.680851 (-640 4285);
PAINT MONO (-640 4285);
FORCEPROP 0 LASTPIN (-650 4325) $PN 101
J 0
(-640 4335);
DISPLAY 0.680851 (-640 4335);
PAINT MONO (-640 4335);
FORCEPROP 0 LASTPIN (-650 4375) $PN 103
J 0
(-640 4385);
DISPLAY 0.680851 (-640 4385);
PAINT MONO (-640 4385);
FORCEPROP 0 LASTPIN (-650 4425) $PN 106
J 0
(-640 4435);
DISPLAY 0.680851 (-640 4435);
PAINT MONO (-640 4435);
FORCEPROP 0 LASTPIN (-650 4475) $PN 108
J 0
(-640 4485);
DISPLAY 0.680851 (-640 4485);
PAINT MONO (-640 4485);
FORCEPROP 0 LASTPIN (-650 4525) $PN 110
J 0
(-640 4535);
DISPLAY 0.680851 (-640 4535);
PAINT MONO (-640 4535);
FORCEPROP 0 LASTPIN (-650 4575) $PN 112
J 0
(-640 4585);
DISPLAY 0.680851 (-640 4585);
PAINT MONO (-640 4585);
FORCEPROP 0 LASTPIN (-650 4625) $PN 114
J 0
(-640 4635);
DISPLAY 0.680851 (-640 4635);
PAINT MONO (-640 4635);
FORCEPROP 0 LASTPIN (-650 4675) $PN 117
J 0
(-640 4685);
DISPLAY 0.680851 (-640 4685);
PAINT MONO (-640 4685);
FORCEPROP 0 LASTPIN (-650 4725) $PN 119
J 0
(-640 4735);
DISPLAY 0.680851 (-640 4735);
PAINT MONO (-640 4735);
FORCEPROP 0 LASTPIN (-650 4775) $PN 121
J 0
(-640 4785);
DISPLAY 0.680851 (-640 4785);
PAINT MONO (-640 4785);
FORCEPROP 0 LASTPIN (-650 4825) $PN 123
J 0
(-640 4835);
DISPLAY 0.680851 (-640 4835);
PAINT MONO (-640 4835);
FORCEPROP 0 LASTPIN (-650 4875) $PN 125
J 0
(-640 4885);
DISPLAY 0.680851 (-640 4885);
PAINT MONO (-640 4885);
FORCEPROP 0 LASTPIN (-650 4925) $PN 128
J 0
(-640 4935);
DISPLAY 0.680851 (-640 4935);
PAINT MONO (-640 4935);
FORCEPROP 0 LASTPIN (-650 4975) $PN 130
J 0
(-640 4985);
DISPLAY 0.680851 (-640 4985);
PAINT MONO (-640 4985);
FORCEPROP 0 LASTPIN (-650 5025) $PN 132
J 0
(-640 5035);
DISPLAY 0.680851 (-640 5035);
PAINT MONO (-640 5035);
FORCEPROP 0 LASTPIN (-650 5075) $PN 134
J 0
(-640 5085);
DISPLAY 0.680851 (-640 5085);
PAINT MONO (-640 5085);
FORCEPROP 0 LASTPIN (-650 5125) $PN 136
J 0
(-640 5135);
DISPLAY 0.680851 (-640 5135);
PAINT MONO (-640 5135);
FORCEPROP 0 LASTPIN (-650 5175) $PN 139
J 0
(-640 5185);
DISPLAY 0.680851 (-640 5185);
PAINT MONO (-640 5185);
FORCEPROP 0 LASTPIN (-650 5225) $PN 141
J 0
(-640 5235);
DISPLAY 0.680851 (-640 5235);
PAINT MONO (-640 5235);
FORCEPROP 0 LASTPIN (-650 5275) $PN 143
J 0
(-640 5285);
DISPLAY 0.680851 (-640 5285);
PAINT MONO (-640 5285);
FORCEPROP 0 LASTPIN (-1850 2025) $PN 151
J 2
(-1860 2035);
DISPLAY 0.680851 (-1860 2035);
PAINT MONO (-1860 2035);
FORCEPROP 0 LASTPIN (-1850 2075) $PN 153
J 2
(-1860 2085);
DISPLAY 0.680851 (-1860 2085);
PAINT MONO (-1860 2085);
FORCEPROP 0 LASTPIN (-1850 2125) $PN 155
J 2
(-1860 2135);
DISPLAY 0.680851 (-1860 2135);
PAINT MONO (-1860 2135);
FORCEPROP 0 LASTPIN (-1850 2175) $PN 158
J 2
(-1860 2185);
DISPLAY 0.680851 (-1860 2185);
PAINT MONO (-1860 2185);
FORCEPROP 0 LASTPIN (-1850 2225) $PN 160
J 2
(-1860 2235);
DISPLAY 0.680851 (-1860 2235);
PAINT MONO (-1860 2235);
FORCEPROP 0 LASTPIN (-1850 2275) $PN 162
J 2
(-1860 2285);
DISPLAY 0.680851 (-1860 2285);
PAINT MONO (-1860 2285);
FORCEPROP 0 LASTPIN (-1850 2325) $PN 164
J 2
(-1860 2335);
DISPLAY 0.680851 (-1860 2335);
PAINT MONO (-1860 2335);
FORCEPROP 0 LASTPIN (-1850 2375) $PN 166
J 2
(-1860 2385);
DISPLAY 0.680851 (-1860 2385);
PAINT MONO (-1860 2385);
FORCEPROP 0 LASTPIN (-1850 2425) $PN 169
J 2
(-1860 2435);
DISPLAY 0.680851 (-1860 2435);
PAINT MONO (-1860 2435);
FORCEPROP 0 LASTPIN (-1850 2475) $PN 171
J 2
(-1860 2485);
DISPLAY 0.680851 (-1860 2485);
PAINT MONO (-1860 2485);
FORCEPROP 0 LASTPIN (-1850 2525) $PN 173
J 2
(-1860 2535);
DISPLAY 0.680851 (-1860 2535);
PAINT MONO (-1860 2535);
FORCEPROP 0 LASTPIN (-1850 2575) $PN 175
J 2
(-1860 2585);
DISPLAY 0.680851 (-1860 2585);
PAINT MONO (-1860 2585);
FORCEPROP 0 LASTPIN (-1850 2625) $PN 177
J 2
(-1860 2635);
DISPLAY 0.680851 (-1860 2635);
PAINT MONO (-1860 2635);
FORCEPROP 0 LASTPIN (-1850 2675) $PN 180
J 2
(-1860 2685);
DISPLAY 0.680851 (-1860 2685);
PAINT MONO (-1860 2685);
FORCEPROP 0 LASTPIN (-1850 2725) $PN 182
J 2
(-1860 2735);
DISPLAY 0.680851 (-1860 2735);
PAINT MONO (-1860 2735);
FORCEPROP 0 LASTPIN (-1850 2775) $PN 184
J 2
(-1860 2785);
DISPLAY 0.680851 (-1860 2785);
PAINT MONO (-1860 2785);
FORCEPROP 0 LASTPIN (-1850 2825) $PN 186
J 2
(-1860 2835);
DISPLAY 0.680851 (-1860 2835);
PAINT MONO (-1860 2835);
FORCEPROP 0 LASTPIN (-1850 2875) $PN 188
J 2
(-1860 2885);
DISPLAY 0.680851 (-1860 2885);
PAINT MONO (-1860 2885);
FORCEPROP 0 LASTPIN (-1850 2925) $PN 191
J 2
(-1860 2935);
DISPLAY 0.680851 (-1860 2935);
PAINT MONO (-1860 2935);
FORCEPROP 0 LASTPIN (-1850 2975) $PN 193
J 2
(-1860 2985);
DISPLAY 0.680851 (-1860 2985);
PAINT MONO (-1860 2985);
FORCEPROP 0 LASTPIN (-1850 3025) $PN 195
J 2
(-1860 3035);
DISPLAY 0.680851 (-1860 3035);
PAINT MONO (-1860 3035);
FORCEPROP 0 LASTPIN (-1850 3075) $PN 197
J 2
(-1860 3085);
DISPLAY 0.680851 (-1860 3085);
PAINT MONO (-1860 3085);
FORCEPROP 0 LASTPIN (-1850 3125) $PN 199
J 2
(-1860 3135);
DISPLAY 0.680851 (-1860 3135);
PAINT MONO (-1860 3135);
FORCEPROP 0 LASTPIN (-1850 3175) $PN 202
J 2
(-1860 3185);
DISPLAY 0.680851 (-1860 3185);
PAINT MONO (-1860 3185);
FORCEPROP 0 LASTPIN (-1850 3225) $PN 204
J 2
(-1860 3235);
DISPLAY 0.680851 (-1860 3235);
PAINT MONO (-1860 3235);
FORCEPROP 0 LASTPIN (-1850 3275) $PN 206
J 2
(-1860 3285);
DISPLAY 0.680851 (-1860 3285);
PAINT MONO (-1860 3285);
FORCEPROP 0 LASTPIN (-1850 3325) $PN 208
J 2
(-1860 3335);
DISPLAY 0.680851 (-1860 3335);
PAINT MONO (-1860 3335);
FORCEPROP 0 LASTPIN (-1850 3375) $PN 210
J 2
(-1860 3385);
DISPLAY 0.680851 (-1860 3385);
PAINT MONO (-1860 3385);
FORCEPROP 0 LASTPIN (-1850 3425) $PN 212
J 2
(-1860 3435);
DISPLAY 0.680851 (-1860 3435);
PAINT MONO (-1860 3435);
FORCEPROP 0 LASTPIN (-1850 3475) $PN 214
J 2
(-1860 3485);
DISPLAY 0.680851 (-1860 3485);
PAINT MONO (-1860 3485);
FORCEPROP 0 LASTPIN (-1850 3525) $PN 216
J 2
(-1860 3535);
DISPLAY 0.680851 (-1860 3535);
PAINT MONO (-1860 3535);
FORCEPROP 0 LASTPIN (-1850 3575) $PN 219
J 2
(-1860 3585);
DISPLAY 0.680851 (-1860 3585);
PAINT MONO (-1860 3585);
FORCEPROP 0 LASTPIN (-1850 3625) $PN 222
J 2
(-1860 3635);
DISPLAY 0.680851 (-1860 3635);
PAINT MONO (-1860 3635);
FORCEPROP 0 LASTPIN (-1850 3675) $PN 224
J 2
(-1860 3685);
DISPLAY 0.680851 (-1860 3685);
PAINT MONO (-1860 3685);
FORCEPROP 0 LASTPIN (-1850 3725) $PN 226
J 2
(-1860 3735);
DISPLAY 0.680851 (-1860 3735);
PAINT MONO (-1860 3735);
FORCEPROP 0 LASTPIN (-1850 3775) $PN 228
J 2
(-1860 3785);
DISPLAY 0.680851 (-1860 3785);
PAINT MONO (-1860 3785);
FORCEPROP 0 LASTPIN (-1850 3825) $PN 230
J 2
(-1860 3835);
DISPLAY 0.680851 (-1860 3835);
PAINT MONO (-1860 3835);
FORCEPROP 0 LASTPIN (-1850 3875) $PN 233
J 2
(-1860 3885);
DISPLAY 0.680851 (-1860 3885);
PAINT MONO (-1860 3885);
FORCEPROP 0 LASTPIN (-1850 3925) $PN 235
J 2
(-1860 3935);
DISPLAY 0.680851 (-1860 3935);
PAINT MONO (-1860 3935);
FORCEPROP 0 LASTPIN (-1850 3975) $PN 237
J 2
(-1860 3985);
DISPLAY 0.680851 (-1860 3985);
PAINT MONO (-1860 3985);
FORCEPROP 0 LASTPIN (-1850 4025) $PN 240
J 2
(-1860 4035);
DISPLAY 0.680851 (-1860 4035);
PAINT MONO (-1860 4035);
FORCEPROP 0 LASTPIN (-1850 4075) $PN 242
J 2
(-1860 4085);
DISPLAY 0.680851 (-1860 4085);
PAINT MONO (-1860 4085);
FORCEPROP 0 LASTPIN (-1850 4125) $PN 244
J 2
(-1860 4135);
DISPLAY 0.680851 (-1860 4135);
PAINT MONO (-1860 4135);
FORCEPROP 0 LASTPIN (-1850 4175) $PN 246
J 2
(-1860 4185);
DISPLAY 0.680851 (-1860 4185);
PAINT MONO (-1860 4185);
FORCEPROP 0 LASTPIN (-1850 4225) $PN 248
J 2
(-1860 4235);
DISPLAY 0.680851 (-1860 4235);
PAINT MONO (-1860 4235);
FORCEPROP 0 LASTPIN (-1850 4275) $PN 251
J 2
(-1860 4285);
DISPLAY 0.680851 (-1860 4285);
PAINT MONO (-1860 4285);
FORCEPROP 0 LASTPIN (-1850 4325) $PN 253
J 2
(-1860 4335);
DISPLAY 0.680851 (-1860 4335);
PAINT MONO (-1860 4335);
FORCEPROP 0 LASTPIN (-1850 4375) $PN 255
J 2
(-1860 4385);
DISPLAY 0.680851 (-1860 4385);
PAINT MONO (-1860 4385);
FORCEPROP 0 LASTPIN (-1850 4425) $PN 257
J 2
(-1860 4435);
DISPLAY 0.680851 (-1860 4435);
PAINT MONO (-1860 4435);
FORCEPROP 0 LASTPIN (-1850 4475) $PN 259
J 2
(-1860 4485);
DISPLAY 0.680851 (-1860 4485);
PAINT MONO (-1860 4485);
FORCEPROP 0 LASTPIN (-1850 4525) $PN 262
J 2
(-1860 4535);
DISPLAY 0.680851 (-1860 4535);
PAINT MONO (-1860 4535);
FORCEPROP 0 LASTPIN (-1850 4575) $PN 264
J 2
(-1860 4585);
DISPLAY 0.680851 (-1860 4585);
PAINT MONO (-1860 4585);
FORCEPROP 0 LASTPIN (-1850 4625) $PN 266
J 2
(-1860 4635);
DISPLAY 0.680851 (-1860 4635);
PAINT MONO (-1860 4635);
FORCEPROP 0 LASTPIN (-1850 4675) $PN 268
J 2
(-1860 4685);
DISPLAY 0.680851 (-1860 4685);
PAINT MONO (-1860 4685);
FORCEPROP 0 LASTPIN (-1850 4725) $PN 270
J 2
(-1860 4735);
DISPLAY 0.680851 (-1860 4735);
PAINT MONO (-1860 4735);
FORCEPROP 0 LASTPIN (-1850 4775) $PN 273
J 2
(-1860 4785);
DISPLAY 0.680851 (-1860 4785);
PAINT MONO (-1860 4785);
FORCEPROP 0 LASTPIN (-1850 4825) $PN 275
J 2
(-1860 4835);
DISPLAY 0.680851 (-1860 4835);
PAINT MONO (-1860 4835);
FORCEPROP 0 LASTPIN (-1850 4875) $PN 277
J 2
(-1860 4885);
DISPLAY 0.680851 (-1860 4885);
PAINT MONO (-1860 4885);
FORCEPROP 0 LASTPIN (-1850 4925) $PN 279
J 2
(-1860 4935);
DISPLAY 0.680851 (-1860 4935);
PAINT MONO (-1860 4935);
FORCEPROP 0 LASTPIN (-1850 4975) $PN 281
J 2
(-1860 4985);
DISPLAY 0.680851 (-1860 4985);
PAINT MONO (-1860 4985);
FORCEPROP 0 LASTPIN (-1850 5025) $PN 284
J 2
(-1860 5035);
DISPLAY 0.680851 (-1860 5035);
PAINT MONO (-1860 5035);
FORCEPROP 0 LASTPIN (-1850 5075) $PN 286
J 2
(-1860 5085);
DISPLAY 0.680851 (-1860 5085);
PAINT MONO (-1860 5085);
FORCEPROP 0 LASTPIN (-1850 5125) $PN 288
J 2
(-1860 5135);
DISPLAY 0.680851 (-1860 5135);
PAINT MONO (-1860 5135);
FORCEPROP 2 LAST VALUE SCONN288_DDR506112002KQ
J 0
(-1700 5650);
DISPLAY 0.489362 (-1700 5650);
PAINT SKYBLUE (-1700 5650);
FORCEPROP 2 LAST PART_TYPE SMLF
J 0
(-1700 5700);
DISPLAY 1.021277 (-1700 5700);
FORCEPROP 1 LAST MATERIAL IO
J 0
(-1700 5450);
DISPLAY 0.468085 (-1700 5450);
PAINT SKYBLUE (-1700 5450);
FORCEPROP 1 LAST PART_NUMBER DFHST8FS479
J 0
(-1700 5525);
DISPLAY 0.468085 (-1700 5525);
PAINT SKYBLUE (-1700 5525);
FORCEPROP 1 LAST CDS_LMAN_SYM_OUTLINE -450,1800,450,-1750
J 0
(-1250 3625);
DISPLAY 0.468085 (-1250 3625);
PAINT GREEN (-1250 3625);
DISPLAY INVISIBLE (-1250 3625);
FORCEPROP 1 LAST PATH I139
J 0
(-1250 3625);
DISPLAY 0.723404 (-1250 3625);
PAINT GREEN (-1250 3625);
DISPLAY INVISIBLE (-1250 3625);
FORCEPROP 1 LAST NEEDS_NO_SIZE TRUE
J 0
(-1250 3625);
DISPLAY 0.723404 (-1250 3625);
PAINT GREEN (-1250 3625);
DISPLAY INVISIBLE (-1250 3625);
FORCEPROP 2 LAST CDS_LIB pure_quanta
J 0
(-1250 3625);
DISPLAY INVISIBLE (-1250 3625);
FORCEADD OFFPAGE..1
(-8300 4175);
FORCEPROP 2 LAST $XR0 47 
J 0
(-8521 4175);
DISPLAY 0.638298 (-8521 4175);
PAINT MONO (-8521 4175);
FORCEPROP 2 LAST CDS_LIB mstr_standard
J 0
(-8300 4175);
DISPLAY 0.808511 (-8300 4175);
DISPLAY INVISIBLE (-8300 4175);
FORCEPROP 1 LAST OFFPAGE TRUE
J 0
(-7975 4050);
DISPLAY 0.872340 (-7975 4050);
PAINT GREEN (-7975 4050);
DISPLAY INVISIBLE (-7975 4050);
FORCEPROP 1 LAST COMMENT_BODY TRUE
J 0
(-8175 4075);
DISPLAY 0.872340 (-8175 4075);
PAINT GREEN (-8175 4075);
DISPLAY INVISIBLE (-8175 4075);
FORCEPROP 2 LAST PATH I14
J 0
(-8500 4225);
DISPLAY 1.021277 (-8500 4225);
DISPLAY INVISIBLE (-8500 4225);
FORCEADD OFFPAGE..1
(-8300 4225);
FORCEPROP 2 LAST $XR0 47 
J 0
(-8521 4225);
DISPLAY 0.638298 (-8521 4225);
PAINT MONO (-8521 4225);
FORCEPROP 2 LAST CDS_LIB mstr_standard
J 0
(-8300 4225);
DISPLAY 0.723404 (-8300 4225);
PAINT MONO (-8300 4225);
DISPLAY INVISIBLE (-8300 4225);
FORCEPROP 1 LAST OFFPAGE TRUE
J 0
(-7975 4100);
DISPLAY 0.872340 (-7975 4100);
PAINT GREEN (-7975 4100);
DISPLAY INVISIBLE (-7975 4100);
FORCEPROP 1 LAST COMMENT_BODY TRUE
J 0
(-8175 4125);
DISPLAY 0.872340 (-8175 4125);
PAINT GREEN (-8175 4125);
DISPLAY INVISIBLE (-8175 4125);
FORCEPROP 2 LAST PATH I15
J 0
(-8500 4275);
DISPLAY 1.021277 (-8500 4275);
DISPLAY INVISIBLE (-8500 4275);
FORCEADD OFFPAGE..1
(-8300 4375);
FORCEPROP 2 LAST $XR0 47 
J 0
(-8521 4375);
DISPLAY 0.638298 (-8521 4375);
PAINT MONO (-8521 4375);
FORCEPROP 2 LAST CDS_LIB mstr_standard
J 0
(-8300 4375);
DISPLAY 0.723404 (-8300 4375);
PAINT MONO (-8300 4375);
DISPLAY INVISIBLE (-8300 4375);
FORCEPROP 1 LAST OFFPAGE TRUE
J 0
(-7975 4250);
DISPLAY 0.872340 (-7975 4250);
PAINT GREEN (-7975 4250);
DISPLAY INVISIBLE (-7975 4250);
FORCEPROP 1 LAST COMMENT_BODY TRUE
J 0
(-8175 4275);
DISPLAY 0.872340 (-8175 4275);
PAINT GREEN (-8175 4275);
DISPLAY INVISIBLE (-8175 4275);
FORCEPROP 2 LAST PATH I16
J 0
(-8500 4425);
DISPLAY 1.021277 (-8500 4425);
DISPLAY INVISIBLE (-8500 4425);
FORCEADD OFFPAGE..1
(-8300 4325);
FORCEPROP 2 LAST $XR0 47 
J 0
(-8521 4325);
DISPLAY 0.638298 (-8521 4325);
PAINT MONO (-8521 4325);
FORCEPROP 2 LAST CDS_LIB mstr_standard
J 0
(-8300 4325);
DISPLAY 0.808511 (-8300 4325);
DISPLAY INVISIBLE (-8300 4325);
FORCEPROP 1 LAST OFFPAGE TRUE
J 0
(-7975 4200);
DISPLAY 0.872340 (-7975 4200);
PAINT GREEN (-7975 4200);
DISPLAY INVISIBLE (-7975 4200);
FORCEPROP 1 LAST COMMENT_BODY TRUE
J 0
(-8175 4225);
DISPLAY 0.872340 (-8175 4225);
PAINT GREEN (-8175 4225);
DISPLAY INVISIBLE (-8175 4225);
FORCEPROP 2 LAST PATH I17
J 0
(-8500 4375);
DISPLAY 1.021277 (-8500 4375);
DISPLAY INVISIBLE (-8500 4375);
FORCEADD OFFPAGE..6
(-8300 2775);
FORCEPROP 2 LAST $XR5 136 
J 0
(-9180 2775);
DISPLAY 0.638298 (-9180 2775);
PAINT MONO (-9180 2775);
FORCEPROP 2 LAST $XR4 108 
J 0
(-9060 2775);
DISPLAY 0.638298 (-9060 2775);
PAINT MONO (-9060 2775);
FORCEPROP 2 LAST $XR3 106 
J 0
(-8940 2775);
DISPLAY 0.638298 (-8940 2775);
PAINT MONO (-8940 2775);
FORCEPROP 2 LAST $XR2 105 
J 0
(-8820 2775);
DISPLAY 0.638298 (-8820 2775);
PAINT MONO (-8820 2775);
FORCEPROP 2 LAST $XR1 104 
J 0
(-8700 2775);
DISPLAY 0.638298 (-8700 2775);
PAINT MONO (-8700 2775);
FORCEPROP 2 LAST $XR0 103 
J 0
(-8580 2775);
DISPLAY 0.638298 (-8580 2775);
PAINT MONO (-8580 2775);
FORCEPROP 2 LAST CDS_LIB mstr_standard
J 0
(-8300 2775);
DISPLAY 0.808511 (-8300 2775);
DISPLAY INVISIBLE (-8300 2775);
FORCEPROP 1 LAST OFFPAGE TRUE
J 0
(-7975 2650);
DISPLAY 0.872340 (-7975 2650);
PAINT GREEN (-7975 2650);
DISPLAY INVISIBLE (-7975 2650);
FORCEPROP 1 LAST COMMENT_BODY TRUE
J 0
(-8200 2700);
DISPLAY 0.872340 (-8200 2700);
PAINT GREEN (-8200 2700);
DISPLAY INVISIBLE (-8200 2700);
FORCEPROP 2 LAST PATH I179
J 0
(-8600 2825);
DISPLAY 1.021277 (-8600 2825);
DISPLAY INVISIBLE (-8600 2825);
FORCEADD OFFPAGE..1
(-8300 4525);
FORCEPROP 2 LAST $XR0 47 
J 0
(-8521 4525);
DISPLAY 0.638298 (-8521 4525);
PAINT MONO (-8521 4525);
FORCEPROP 2 LAST CDS_LIB mstr_standard
J 0
(-8300 4525);
DISPLAY 0.723404 (-8300 4525);
PAINT MONO (-8300 4525);
DISPLAY INVISIBLE (-8300 4525);
FORCEPROP 1 LAST OFFPAGE TRUE
J 0
(-7975 4400);
DISPLAY 0.872340 (-7975 4400);
PAINT GREEN (-7975 4400);
DISPLAY INVISIBLE (-7975 4400);
FORCEPROP 1 LAST COMMENT_BODY TRUE
J 0
(-8175 4425);
DISPLAY 0.872340 (-8175 4425);
PAINT GREEN (-8175 4425);
DISPLAY INVISIBLE (-8175 4425);
FORCEPROP 2 LAST PATH I18
J 0
(-8500 4575);
DISPLAY 1.021277 (-8500 4575);
DISPLAY INVISIBLE (-8500 4575);
FORCEADD Q_CAP..1
R 2
(-8675 3150);
FORCEPROP 1 LAST LOCATION C176
J 2
(-8725 3250);
DISPLAY 0.489362 (-8725 3250);
PAINT SKYBLUE (-8725 3250);
FORCEPROP 0 LAST $SEC 1
J 0
(-8725 3300);
DISPLAY 0.680851 (-8725 3300);
PAINT MONO (-8725 3300);
DISPLAY INVISIBLE (-8725 3300);
FORCEPROP 0 LAST CDS_SEC 1
J 0
(-8725 3300);
DISPLAY 1.021277 (-8725 3300);
DISPLAY INVISIBLE (-8725 3300);
FORCEPROP 1 LASTPIN (-8675 3250) $PN 1
J 2
(-8685 3230);
DISPLAY 0.489362 (-8685 3230);
PAINT MONO (-8685 3230);
FORCEPROP 1 LASTPIN (-8675 3050) $PN 2
J 2
(-8685 3030);
DISPLAY 0.489362 (-8685 3030);
PAINT MONO (-8685 3030);
FORCEPROP 1 LAST MATERIAL X7R
J 2
(-8725 3050);
DISPLAY 0.489362 (-8725 3050);
PAINT SKYBLUE (-8725 3050);
FORCEPROP 1 LAST TOLERANCE 10%
J 2
(-8725 3100);
DISPLAY 0.489362 (-8725 3100);
PAINT SKYBLUE (-8725 3100);
FORCEPROP 1 LAST VALUE 0.1UF
J 2
(-8725 3200);
DISPLAY 0.489362 (-8725 3200);
PAINT SKYBLUE (-8725 3200);
FORCEPROP 1 LAST VOLTAGE 25V
J 2
(-8725 3150);
DISPLAY 0.489362 (-8725 3150);
PAINT SKYBLUE (-8725 3150);
FORCEPROP 1 LAST PACK_TYPE 0402
J 2
(-8725 2950);
DISPLAY 0.489362 (-8725 2950);
PAINT SKYBLUE (-8725 2950);
FORCEPROP 1 LAST PART_NUMBER CH4104K1B00
J 2
(-8725 3000);
DISPLAY 0.489362 (-8725 3000);
PAINT SKYBLUE (-8725 3000);
FORCEPROP 2 LAST CDS_LIB pure_quanta
J 0
(-8675 3150);
DISPLAY INVISIBLE (-8675 3150);
FORCEPROP 0 LAST BOM_COST MEM
J 2
(-8730 3295);
DISPLAY 0.595745 (-8730 3295);
PAINT MONO (-8730 3295);
DISPLAY INVISIBLE (-8730 3295);
FORCEPROP 1 LAST PATH I185
J 2
(-8725 3300);
DISPLAY 0.978723 (-8725 3300);
PAINT WHITE (-8725 3300);
DISPLAY INVISIBLE (-8725 3300);
FORCEPROP 0 LAST ROOM MEM_CH_A_CPU0_DIMM1
J 2
(-8730 3295);
DISPLAY 0.595745 (-8730 3295);
PAINT RED (-8730 3295);
DISPLAY INVISIBLE (-8730 3295);
FORCEADD GND..1
(-8675 2925);
FORCEPROP 3 LASTPIN (-8675 2975) SIG_NAME GND\g
J 0
(-8665 2985);
DISPLAY 0.659574 (-8665 2985);
PAINT MONO (-8665 2985);
DISPLAY INVISIBLE (-8665 2985);
FORCEPROP 2 LAST CDS_LIB mstr_symbols
J 0
(-8675 2925);
DISPLAY 0.808511 (-8675 2925);
DISPLAY INVISIBLE (-8675 2925);
FORCEPROP 1 LAST SIZE 1B
J 0
(-8600 2875);
DISPLAY 0.723404 (-8600 2875);
PAINT GREEN (-8600 2875);
DISPLAY INVISIBLE (-8600 2875);
FORCEPROP 2 LAST BOM_COST MEM
J 0
(-8650 3050);
DISPLAY 0.659574 (-8650 3050);
DISPLAY INVISIBLE (-8650 3050);
FORCEPROP 1 LAST BODY_TYPE PLUMBING
J 0
(-8720 2882);
DISPLAY 0.276596 (-8720 2882);
PAINT GREEN (-8720 2882);
DISPLAY INVISIBLE (-8720 2882);
FORCEPROP 1 LAST PATH I186
J 0
(-8600 2925);
DISPLAY 0.872340 (-8600 2925);
PAINT AQUA (-8600 2925);
DISPLAY INVISIBLE (-8600 2925);
FORCEPROP 1 LAST VOLTAGE 0
J 0
(-8695 3020);
DISPLAY 0.829787 (-8695 3020);
PAINT SKYBLUE (-8695 3020);
DISPLAY INVISIBLE (-8695 3020);
FORCEPROP 2 LAST ROOM MEM_EFGH_DECOUPLING_CAPS
J 0
(-8650 3000);
DISPLAY 0.659574 (-8650 3000);
PAINT RED (-8650 3000);
DISPLAY INVISIBLE (-8650 3000);
FORCEPROP 1 LAST HDL_POWER GND
J 0
(-8675 3075);
DISPLAY 0.723404 (-8675 3075);
PAINT GREEN (-8675 3075);
DISPLAY INVISIBLE (-8675 3075);
FORCEADD OFFPAGE..6
(-9025 2075);
FORCEPROP 2 LAST $XR5 81 
J 0
(-9305 1967);
DISPLAY 0.638298 (-9305 1967);
PAINT MONO (-9305 1967);
FORCEPROP 2 LAST $XR4 108 
J 0
(-9305 2147);
DISPLAY 0.638298 (-9305 2147);
PAINT MONO (-9305 2147);
FORCEPROP 2 LAST $XR3 106 
J 0
(-9305 2003);
DISPLAY 0.638298 (-9305 2003);
PAINT MONO (-9305 2003);
FORCEPROP 2 LAST $XR2 105 
J 0
(-9305 2111);
DISPLAY 0.638298 (-9305 2111);
PAINT MONO (-9305 2111);
FORCEPROP 2 LAST $XR1 104 
J 0
(-9305 2039);
DISPLAY 0.638298 (-9305 2039);
PAINT MONO (-9305 2039);
FORCEPROP 2 LAST $XR0 103 
J 0
(-9305 2075);
DISPLAY 0.638298 (-9305 2075);
PAINT MONO (-9305 2075);
FORCEPROP 2 LAST CDS_LIB mstr_standard
J 0
(-9025 2075);
DISPLAY INVISIBLE (-9025 2075);
FORCEPROP 1 LAST OFFPAGE TRUE
J 0
(-8700 1950);
DISPLAY 0.872340 (-8700 1950);
PAINT GREEN (-8700 1950);
DISPLAY INVISIBLE (-8700 1950);
FORCEPROP 1 LAST COMMENT_BODY TRUE
J 0
(-8925 2000);
DISPLAY 0.872340 (-8925 2000);
PAINT GREEN (-8925 2000);
DISPLAY INVISIBLE (-8925 2000);
FORCEPROP 2 LAST PATH I187
J 0
(-8975 2150);
DISPLAY 1.021277 (-8975 2150);
DISPLAY INVISIBLE (-8975 2150);
FORCEADD Q_RES..1
R 2
(-8500 2075);
FORCEPROP 1 LAST LOCATION R313
J 2
(-8450 2125);
DISPLAY 0.489362 (-8450 2125);
PAINT SKYBLUE (-8450 2125);
FORCEPROP 0 LAST $SEC 1
J 0
(-8450 2175);
DISPLAY 0.680851 (-8450 2175);
PAINT MONO (-8450 2175);
DISPLAY INVISIBLE (-8450 2175);
FORCEPROP 0 LAST CDS_SEC 1
J 0
(-8450 2175);
DISPLAY 1.021277 (-8450 2175);
DISPLAY INVISIBLE (-8450 2175);
FORCEPROP 1 LASTPIN (-8400 2075) $PN 1
J 2
(-8412 2087);
DISPLAY 0.489362 (-8412 2087);
PAINT MONO (-8412 2087);
FORCEPROP 1 LASTPIN (-8600 2075) $PN 2
J 2
(-8562 2087);
DISPLAY 0.489362 (-8562 2087);
PAINT MONO (-8562 2087);
FORCEPROP 1 LAST VALUE 0
J 0
(-8500 2025);
DISPLAY 0.489362 (-8500 2025);
PAINT SKYBLUE (-8500 2025);
FORCEPROP 2 LAST CDS_LIB pure_quanta
J 0
(-8500 2075);
DISPLAY INVISIBLE (-8500 2075);
FORCEPROP 2 LAST BOM_COST MEM
J 0
(-8525 2225);
DISPLAY 0.744681 (-8525 2225);
PAINT WHITE (-8525 2225);
DISPLAY INVISIBLE (-8525 2225);
FORCEPROP 1 LAST PATH I188
J 2
(-8450 2225);
DISPLAY 0.978723 (-8450 2225);
PAINT WHITE (-8450 2225);
DISPLAY INVISIBLE (-8450 2225);
FORCEPROP 1 LAST WATTAGE 1/16W
J 0
(-8425 2000);
DISPLAY 0.489362 (-8425 2000);
PAINT SKYBLUE (-8425 2000);
DISPLAY INVISIBLE (-8425 2000);
FORCEPROP 1 LAST MATERIAL CHIP
J 0
(-8675 2050);
DISPLAY 0.489362 (-8675 2050);
PAINT SKYBLUE (-8675 2050);
DISPLAY INVISIBLE (-8675 2050);
FORCEPROP 1 LAST TOLERANCE 5%
J 2
(-8375 2050);
DISPLAY 0.489362 (-8375 2050);
PAINT SKYBLUE (-8375 2050);
DISPLAY INVISIBLE (-8375 2050);
FORCEPROP 1 LAST PART_NUMBER CS00002JB38
J 0
(-8600 2125);
DISPLAY 0.489362 (-8600 2125);
PAINT SKYBLUE (-8600 2125);
DISPLAY INVISIBLE (-8600 2125);
FORCEPROP 1 LAST PACK_TYPE 0402LF
J 0
(-8675 2000);
DISPLAY 0.489362 (-8675 2000);
PAINT SKYBLUE (-8675 2000);
DISPLAY INVISIBLE (-8675 2000);
FORCEPROP 2 LAST ROOM RST_CPU0_PLD_TO_DIMM
J 0
(-8525 2175);
DISPLAY 0.744681 (-8525 2175);
PAINT RED (-8525 2175);
DISPLAY INVISIBLE (-8525 2175);
FORCEADD VCC_CORE..1
(-8375 2400);
FORCEPROP 3 LASTPIN (-8375 2350) SIG_NAME P3V3_STBY\g
J 0
(-8365 2360);
DISPLAY 0.659574 (-8365 2360);
PAINT MONO (-8365 2360);
DISPLAY INVISIBLE (-8365 2360);
FORCEPROP 1 LAST HDL_POWER P3V3_STBY
J 1
(-8375 2450);
DISPLAY 0.489362 (-8375 2450);
PAINT GREEN (-8375 2450);
FORCEPROP 2 LAST CDS_LIB mstr_symbols
J 0
(-8375 2400);
DISPLAY INVISIBLE (-8375 2400);
FORCEPROP 1 LAST PATH I189
J 0
(-8325 2425);
DISPLAY 0.872340 (-8325 2425);
PAINT AQUA (-8325 2425);
DISPLAY INVISIBLE (-8325 2425);
FORCEPROP 0 LAST VOLTAGE 3.3
J 0
(-8650 2550);
DISPLAY 1.021277 (-8650 2550);
PAINT SKYBLUE (-8650 2550);
DISPLAY INVISIBLE (-8650 2550);
FORCEPROP 2 LAST ROOM PVCCINFAON_CPU0_CTRL
J 0
(-8375 2500);
DISPLAY 0.808511 (-8375 2500);
PAINT RED (-8375 2500);
DISPLAY INVISIBLE (-8375 2500);
FORCEADD OFFPAGE..1
(-8300 4475);
FORCEPROP 2 LAST $XR0 47 
J 0
(-8521 4475);
DISPLAY 0.638298 (-8521 4475);
PAINT MONO (-8521 4475);
FORCEPROP 2 LAST CDS_LIB mstr_standard
J 0
(-8300 4475);
DISPLAY 0.808511 (-8300 4475);
DISPLAY INVISIBLE (-8300 4475);
FORCEPROP 1 LAST OFFPAGE TRUE
J 0
(-7975 4350);
DISPLAY 0.872340 (-7975 4350);
PAINT GREEN (-7975 4350);
DISPLAY INVISIBLE (-7975 4350);
FORCEPROP 1 LAST COMMENT_BODY TRUE
J 0
(-8175 4375);
DISPLAY 0.872340 (-8175 4375);
PAINT GREEN (-8175 4375);
DISPLAY INVISIBLE (-8175 4375);
FORCEPROP 2 LAST PATH I19
J 0
(-8500 4525);
DISPLAY 1.021277 (-8500 4525);
DISPLAY INVISIBLE (-8500 4525);
FORCEADD Q_RES..2
(-8375 2225);
FORCEPROP 1 LAST LOCATION R114
J 0
(-8330 2350);
DISPLAY 0.489362 (-8330 2350);
PAINT SKYBLUE (-8330 2350);
FORCEPROP 0 LAST $SEC 1
J 0
(-8325 2400);
DISPLAY 0.680851 (-8325 2400);
PAINT MONO (-8325 2400);
DISPLAY INVISIBLE (-8325 2400);
FORCEPROP 0 LAST CDS_SEC 1
J 0
(-8325 2400);
DISPLAY 1.021277 (-8325 2400);
DISPLAY INVISIBLE (-8325 2400);
FORCEPROP 1 LASTPIN (-8375 2325) $PN 1
J 0
(-8370 2287);
DISPLAY 0.489362 (-8370 2287);
PAINT MONO (-8370 2287);
FORCEPROP 1 LASTPIN (-8375 2125) $PN 2
J 0
(-8370 2135);
DISPLAY 0.489362 (-8370 2135);
PAINT MONO (-8370 2135);
FORCEPROP 1 LAST TOLERANCE 5%
J 0
(-8325 2275);
DISPLAY 0.489362 (-8325 2275);
PAINT SKYBLUE (-8325 2275);
FORCEPROP 1 LAST VALUE 1K
J 0
(-8330 2300);
DISPLAY 0.489362 (-8330 2300);
PAINT SKYBLUE (-8330 2300);
FORCEPROP 1 LAST WATTAGE 1/16W
J 0
(-8325 2250);
DISPLAY 0.489362 (-8325 2250);
PAINT SKYBLUE (-8325 2250);
FORCEPROP 1 LAST MATERIAL EMPTY
J 0
(-8325 2225);
DISPLAY 0.489362 (-8325 2225);
PAINT RED (-8325 2225);
FORCEPROP 1 LAST PACK_TYPE 0402LF
J 0
(-8325 2175);
DISPLAY 0.489362 (-8325 2175);
PAINT SKYBLUE (-8325 2175);
FORCEPROP 2 LAST CDS_LIB pure_quanta
J 0
(-8375 2225);
DISPLAY INVISIBLE (-8375 2225);
FORCEPROP 2 LAST BOM_COST MEM
J 0
(-8325 2400);
DISPLAY 0.808511 (-8325 2400);
DISPLAY INVISIBLE (-8325 2400);
FORCEPROP 1 LAST PATH I190
J 0
(-8325 2400);
DISPLAY 0.978723 (-8325 2400);
PAINT WHITE (-8325 2400);
DISPLAY INVISIBLE (-8325 2400);
FORCEPROP 1 LAST PART_NUMBER TMP_QCS21002JB34
J 0
(-8325 2200);
DISPLAY 0.489362 (-8325 2200);
PAINT SKYBLUE (-8325 2200);
DISPLAY INVISIBLE (-8325 2200);
FORCEPROP 2 LAST ROOM MEM_CH_A_CPU0_DIMM1
J 0
(-8325 2450);
DISPLAY 0.808511 (-8325 2450);
PAINT RED (-8325 2450);
DISPLAY INVISIBLE (-8325 2450);
FORCEADD OFFPAGE..2
(-2475 4550);
FORCEPROP 2 LAST $XR0 47 
J 0
(-2286 4550);
DISPLAY 0.638298 (-2286 4550);
PAINT MONO (-2286 4550);
FORCEPROP 2 LAST PATH I191
J 0
(-2275 4600);
DISPLAY 0.680851 (-2275 4600);
DISPLAY INVISIBLE (-2275 4600);
FORCEPROP 2 LAST CDS_LIB mstr_standard
J 0
(-2475 4550);
DISPLAY 0.723404 (-2475 4550);
PAINT MONO (-2475 4550);
DISPLAY INVISIBLE (-2475 4550);
FORCEPROP 1 LAST OFFPAGE TRUE
J 0
(-2150 4425);
DISPLAY 0.723404 (-2150 4425);
PAINT GREEN (-2150 4425);
DISPLAY INVISIBLE (-2150 4425);
FORCEPROP 1 LAST COMMENT_BODY TRUE
J 0
(-2520 4455);
DISPLAY 0.872340 (-2520 4455);
PAINT GREEN (-2520 4455);
DISPLAY INVISIBLE (-2520 4455);
FORCEADD OFFPAGE..2
(-2475 4500);
FORCEPROP 2 LAST $XR0 47 
J 0
(-2286 4500);
DISPLAY 0.638298 (-2286 4500);
PAINT MONO (-2286 4500);
FORCEPROP 2 LAST PATH I192
J 0
(-2275 4550);
DISPLAY 0.680851 (-2275 4550);
DISPLAY INVISIBLE (-2275 4550);
FORCEPROP 2 LAST CDS_LIB mstr_standard
J 0
(-2475 4500);
DISPLAY 0.723404 (-2475 4500);
PAINT MONO (-2475 4500);
DISPLAY INVISIBLE (-2475 4500);
FORCEPROP 1 LAST OFFPAGE TRUE
J 0
(-2150 4375);
DISPLAY 0.723404 (-2150 4375);
PAINT GREEN (-2150 4375);
DISPLAY INVISIBLE (-2150 4375);
FORCEPROP 1 LAST COMMENT_BODY TRUE
J 0
(-2520 4405);
DISPLAY 0.872340 (-2520 4405);
PAINT GREEN (-2520 4405);
DISPLAY INVISIBLE (-2520 4405);
FORCEADD OFFPAGE..2
(-2475 3500);
FORCEPROP 2 LAST $XR0 47 
J 0
(-2286 3500);
DISPLAY 0.638298 (-2286 3500);
PAINT MONO (-2286 3500);
FORCEPROP 2 LAST PATH I193
J 0
(-2275 3550);
DISPLAY 0.680851 (-2275 3550);
DISPLAY INVISIBLE (-2275 3550);
FORCEPROP 2 LAST CDS_LIB mstr_standard
J 0
(-2475 3500);
DISPLAY 0.723404 (-2475 3500);
PAINT MONO (-2475 3500);
DISPLAY INVISIBLE (-2475 3500);
FORCEPROP 1 LAST OFFPAGE TRUE
J 0
(-2150 3375);
DISPLAY 0.723404 (-2150 3375);
PAINT GREEN (-2150 3375);
DISPLAY INVISIBLE (-2150 3375);
FORCEPROP 1 LAST COMMENT_BODY TRUE
J 0
(-2520 3405);
DISPLAY 0.872340 (-2520 3405);
PAINT GREEN (-2520 3405);
DISPLAY INVISIBLE (-2520 3405);
FORCEADD OFFPAGE..2
(-2475 3450);
FORCEPROP 2 LAST $XR0 47 
J 0
(-2286 3450);
DISPLAY 0.638298 (-2286 3450);
PAINT MONO (-2286 3450);
FORCEPROP 2 LAST PATH I194
J 0
(-2275 3500);
DISPLAY 0.680851 (-2275 3500);
DISPLAY INVISIBLE (-2275 3500);
FORCEPROP 2 LAST CDS_LIB mstr_standard
J 0
(-2475 3450);
DISPLAY 0.723404 (-2475 3450);
PAINT MONO (-2475 3450);
DISPLAY INVISIBLE (-2475 3450);
FORCEPROP 1 LAST OFFPAGE TRUE
J 0
(-2150 3325);
DISPLAY 0.723404 (-2150 3325);
PAINT GREEN (-2150 3325);
DISPLAY INVISIBLE (-2150 3325);
FORCEPROP 1 LAST COMMENT_BODY TRUE
J 0
(-2520 3355);
DISPLAY 0.872340 (-2520 3355);
PAINT GREEN (-2520 3355);
DISPLAY INVISIBLE (-2520 3355);
FORCEADD TAP..1
(-3275 4350);
FORCEPROP 3 LASTPIN (-3325 4350) SIG_NAME M_K_CPU1_SA_DQS_DN<8>
J 0
(-3315 4360);
DISPLAY 0.659574 (-3315 4360);
PAINT MONO (-3315 4360);
DISPLAY INVISIBLE (-3315 4360);
FORCEPROP 1 LASTPIN (-3325 4350) BN 8
J 0
(-3337 4358);
DISPLAY 0.489362 (-3337 4358);
PAINT GREEN (-3337 4358);
FORCEPROP 2 LAST CDS_LIB mstr_standard
J 0
(-3275 4350);
DISPLAY 0.723404 (-3275 4350);
PAINT MONO (-3275 4350);
DISPLAY INVISIBLE (-3275 4350);
FORCEPROP 1 LAST BODY_TYPE PLUMBING
J 0
(-3275 4400);
DISPLAY 0.872340 (-3275 4400);
PAINT GREEN (-3275 4400);
DISPLAY INVISIBLE (-3275 4400);
FORCEPROP 1 LAST HDL_TAP TRUE
J 0
(-2950 4225);
DISPLAY 0.872340 (-2950 4225);
DISPLAY INVISIBLE (-2950 4225);
FORCEPROP 1 LAST PATH I195
J 0
(-3277 4350);
DISPLAY 0.872340 (-3277 4350);
PAINT GREEN (-3277 4350);
DISPLAY INVISIBLE (-3277 4350);
FORCEADD TAP..1
(-3275 4450);
FORCEPROP 3 LASTPIN (-3325 4450) SIG_NAME M_K_CPU1_SA_DQS_DN<9>
J 0
(-3315 4460);
DISPLAY 0.659574 (-3315 4460);
PAINT MONO (-3315 4460);
DISPLAY INVISIBLE (-3315 4460);
FORCEPROP 1 LASTPIN (-3325 4450) BN 9
J 0
(-3337 4458);
DISPLAY 0.489362 (-3337 4458);
PAINT GREEN (-3337 4458);
FORCEPROP 2 LAST CDS_LIB mstr_standard
J 0
(-3275 4450);
DISPLAY 0.723404 (-3275 4450);
PAINT MONO (-3275 4450);
DISPLAY INVISIBLE (-3275 4450);
FORCEPROP 1 LAST BODY_TYPE PLUMBING
J 0
(-3275 4500);
DISPLAY 0.872340 (-3275 4500);
PAINT GREEN (-3275 4500);
DISPLAY INVISIBLE (-3275 4500);
FORCEPROP 1 LAST HDL_TAP TRUE
J 0
(-2950 4325);
DISPLAY 0.872340 (-2950 4325);
DISPLAY INVISIBLE (-2950 4325);
FORCEPROP 1 LAST PATH I196
J 0
(-3277 4450);
DISPLAY 0.872340 (-3277 4450);
PAINT GREEN (-3277 4450);
DISPLAY INVISIBLE (-3277 4450);
FORCEADD TAP..1
(-3475 4500);
FORCEPROP 3 LASTPIN (-3525 4500) SIG_NAME M_K_CPU1_SA_DQS_DP<9>
J 0
(-3515 4510);
DISPLAY 0.659574 (-3515 4510);
PAINT MONO (-3515 4510);
DISPLAY INVISIBLE (-3515 4510);
FORCEPROP 1 LASTPIN (-3525 4500) BN 9
J 0
(-3537 4508);
DISPLAY 0.489362 (-3537 4508);
PAINT GREEN (-3537 4508);
FORCEPROP 2 LAST CDS_LIB mstr_standard
J 0
(-3475 4500);
DISPLAY 0.723404 (-3475 4500);
PAINT MONO (-3475 4500);
DISPLAY INVISIBLE (-3475 4500);
FORCEPROP 1 LAST BODY_TYPE PLUMBING
J 0
(-3475 4550);
DISPLAY 0.872340 (-3475 4550);
PAINT GREEN (-3475 4550);
DISPLAY INVISIBLE (-3475 4550);
FORCEPROP 1 LAST HDL_TAP TRUE
J 0
(-3150 4375);
DISPLAY 0.872340 (-3150 4375);
DISPLAY INVISIBLE (-3150 4375);
FORCEPROP 1 LAST PATH I197
J 0
(-3477 4500);
DISPLAY 0.872340 (-3477 4500);
PAINT GREEN (-3477 4500);
DISPLAY INVISIBLE (-3477 4500);
FORCEADD TAP..1
(-3475 4400);
FORCEPROP 3 LASTPIN (-3525 4400) SIG_NAME M_K_CPU1_SA_DQS_DP<8>
J 0
(-3515 4410);
DISPLAY 0.659574 (-3515 4410);
PAINT MONO (-3515 4410);
DISPLAY INVISIBLE (-3515 4410);
FORCEPROP 1 LASTPIN (-3525 4400) BN 8
J 0
(-3537 4408);
DISPLAY 0.489362 (-3537 4408);
PAINT GREEN (-3537 4408);
FORCEPROP 2 LAST CDS_LIB mstr_standard
J 0
(-3475 4400);
DISPLAY 0.723404 (-3475 4400);
PAINT MONO (-3475 4400);
DISPLAY INVISIBLE (-3475 4400);
FORCEPROP 1 LAST BODY_TYPE PLUMBING
J 0
(-3475 4450);
DISPLAY 0.872340 (-3475 4450);
PAINT GREEN (-3475 4450);
DISPLAY INVISIBLE (-3475 4450);
FORCEPROP 1 LAST HDL_TAP TRUE
J 0
(-3150 4275);
DISPLAY 0.872340 (-3150 4275);
DISPLAY INVISIBLE (-3150 4275);
FORCEPROP 1 LAST PATH I198
J 0
(-3477 4400);
DISPLAY 0.872340 (-3477 4400);
PAINT GREEN (-3477 4400);
DISPLAY INVISIBLE (-3477 4400);
FORCEADD TAP..1
(-3275 4250);
FORCEPROP 3 LASTPIN (-3325 4250) SIG_NAME M_K_CPU1_SA_DQS_DN<7>
J 0
(-3315 4260);
DISPLAY 0.659574 (-3315 4260);
PAINT MONO (-3315 4260);
DISPLAY INVISIBLE (-3315 4260);
FORCEPROP 1 LASTPIN (-3325 4250) BN 7
J 0
(-3337 4258);
DISPLAY 0.489362 (-3337 4258);
PAINT GREEN (-3337 4258);
FORCEPROP 2 LAST CDS_LIB mstr_standard
J 0
(-3275 4250);
DISPLAY 0.723404 (-3275 4250);
PAINT MONO (-3275 4250);
DISPLAY INVISIBLE (-3275 4250);
FORCEPROP 1 LAST BODY_TYPE PLUMBING
J 0
(-3275 4300);
DISPLAY 0.872340 (-3275 4300);
PAINT GREEN (-3275 4300);
DISPLAY INVISIBLE (-3275 4300);
FORCEPROP 1 LAST HDL_TAP TRUE
J 0
(-2950 4125);
DISPLAY 0.872340 (-2950 4125);
DISPLAY INVISIBLE (-2950 4125);
FORCEPROP 1 LAST PATH I199
J 0
(-3277 4250);
DISPLAY 0.872340 (-3277 4250);
PAINT GREEN (-3277 4250);
DISPLAY INVISIBLE (-3277 4250);
FORCEADD OFFPAGE..5
(-8300 1925);
FORCEPROP 2 LAST $XR0 47 
J 0
(-8554 1925);
DISPLAY 0.638298 (-8554 1925);
PAINT MONO (-8554 1925);
FORCEPROP 2 LAST CDS_LIB mstr_standard
J 0
(-8300 1925);
DISPLAY 0.808511 (-8300 1925);
DISPLAY INVISIBLE (-8300 1925);
FORCEPROP 1 LAST OFFPAGE TRUE
J 0
(-7975 1800);
DISPLAY 0.872340 (-7975 1800);
PAINT GREEN (-7975 1800);
DISPLAY INVISIBLE (-7975 1800);
FORCEPROP 1 LAST COMMENT_BODY TRUE
J 0
(-8200 1850);
DISPLAY 0.872340 (-8200 1850);
PAINT GREEN (-8200 1850);
DISPLAY INVISIBLE (-8200 1850);
FORCEPROP 2 LAST PATH I2
J 0
(-8550 1975);
DISPLAY 1.021277 (-8550 1975);
DISPLAY INVISIBLE (-8550 1975);
FORCEADD OFFPAGE..1
(-8300 5375);
FORCEPROP 2 LAST $XR0 47 
J 0
(-8521 5375);
DISPLAY 0.638298 (-8521 5375);
PAINT MONO (-8521 5375);
FORCEPROP 2 LAST CDS_LIB mstr_standard
J 0
(-8300 5375);
DISPLAY 0.723404 (-8300 5375);
PAINT MONO (-8300 5375);
DISPLAY INVISIBLE (-8300 5375);
FORCEPROP 1 LAST OFFPAGE TRUE
J 0
(-7975 5250);
DISPLAY 0.872340 (-7975 5250);
PAINT GREEN (-7975 5250);
DISPLAY INVISIBLE (-7975 5250);
FORCEPROP 1 LAST COMMENT_BODY TRUE
J 0
(-8175 5275);
DISPLAY 0.872340 (-8175 5275);
PAINT GREEN (-8175 5275);
DISPLAY INVISIBLE (-8175 5275);
FORCEPROP 2 LAST PATH I20
J 0
(-8500 5425);
DISPLAY 1.021277 (-8500 5425);
DISPLAY INVISIBLE (-8500 5425);
FORCEADD TAP..1
(-3275 4150);
FORCEPROP 3 LASTPIN (-3325 4150) SIG_NAME M_K_CPU1_SA_DQS_DN<6>
J 0
(-3315 4160);
DISPLAY 0.659574 (-3315 4160);
PAINT MONO (-3315 4160);
DISPLAY INVISIBLE (-3315 4160);
FORCEPROP 1 LASTPIN (-3325 4150) BN 6
J 0
(-3337 4158);
DISPLAY 0.489362 (-3337 4158);
PAINT GREEN (-3337 4158);
FORCEPROP 2 LAST CDS_LIB mstr_standard
J 0
(-3275 4150);
DISPLAY 0.723404 (-3275 4150);
PAINT MONO (-3275 4150);
DISPLAY INVISIBLE (-3275 4150);
FORCEPROP 1 LAST BODY_TYPE PLUMBING
J 0
(-3275 4200);
DISPLAY 0.872340 (-3275 4200);
PAINT GREEN (-3275 4200);
DISPLAY INVISIBLE (-3275 4200);
FORCEPROP 1 LAST HDL_TAP TRUE
J 0
(-2950 4025);
DISPLAY 0.872340 (-2950 4025);
DISPLAY INVISIBLE (-2950 4025);
FORCEPROP 1 LAST PATH I200
J 0
(-3277 4150);
DISPLAY 0.872340 (-3277 4150);
PAINT GREEN (-3277 4150);
DISPLAY INVISIBLE (-3277 4150);
FORCEADD TAP..1
(-3475 4300);
FORCEPROP 3 LASTPIN (-3525 4300) SIG_NAME M_K_CPU1_SA_DQS_DP<7>
J 0
(-3515 4310);
DISPLAY 0.659574 (-3515 4310);
PAINT MONO (-3515 4310);
DISPLAY INVISIBLE (-3515 4310);
FORCEPROP 1 LASTPIN (-3525 4300) BN 7
J 0
(-3537 4308);
DISPLAY 0.489362 (-3537 4308);
PAINT GREEN (-3537 4308);
FORCEPROP 2 LAST CDS_LIB mstr_standard
J 0
(-3475 4300);
DISPLAY 0.723404 (-3475 4300);
PAINT MONO (-3475 4300);
DISPLAY INVISIBLE (-3475 4300);
FORCEPROP 1 LAST BODY_TYPE PLUMBING
J 0
(-3475 4350);
DISPLAY 0.872340 (-3475 4350);
PAINT GREEN (-3475 4350);
DISPLAY INVISIBLE (-3475 4350);
FORCEPROP 1 LAST HDL_TAP TRUE
J 0
(-3150 4175);
DISPLAY 0.872340 (-3150 4175);
DISPLAY INVISIBLE (-3150 4175);
FORCEPROP 1 LAST PATH I201
J 0
(-3477 4300);
DISPLAY 0.872340 (-3477 4300);
PAINT GREEN (-3477 4300);
DISPLAY INVISIBLE (-3477 4300);
FORCEADD TAP..1
(-3475 4200);
FORCEPROP 3 LASTPIN (-3525 4200) SIG_NAME M_K_CPU1_SA_DQS_DP<6>
J 0
(-3515 4210);
DISPLAY 0.659574 (-3515 4210);
PAINT MONO (-3515 4210);
DISPLAY INVISIBLE (-3515 4210);
FORCEPROP 1 LASTPIN (-3525 4200) BN 6
J 0
(-3537 4208);
DISPLAY 0.489362 (-3537 4208);
PAINT GREEN (-3537 4208);
FORCEPROP 2 LAST CDS_LIB mstr_standard
J 0
(-3475 4200);
DISPLAY 0.723404 (-3475 4200);
PAINT MONO (-3475 4200);
DISPLAY INVISIBLE (-3475 4200);
FORCEPROP 1 LAST BODY_TYPE PLUMBING
J 0
(-3475 4250);
DISPLAY 0.872340 (-3475 4250);
PAINT GREEN (-3475 4250);
DISPLAY INVISIBLE (-3475 4250);
FORCEPROP 1 LAST HDL_TAP TRUE
J 0
(-3150 4075);
DISPLAY 0.872340 (-3150 4075);
DISPLAY INVISIBLE (-3150 4075);
FORCEPROP 1 LAST PATH I202
J 0
(-3477 4200);
DISPLAY 0.872340 (-3477 4200);
PAINT GREEN (-3477 4200);
DISPLAY INVISIBLE (-3477 4200);
FORCEADD TAP..1
(-3475 4100);
FORCEPROP 3 LASTPIN (-3525 4100) SIG_NAME M_K_CPU1_SA_DQS_DP<5>
J 0
(-3515 4110);
DISPLAY 0.659574 (-3515 4110);
PAINT MONO (-3515 4110);
DISPLAY INVISIBLE (-3515 4110);
FORCEPROP 1 LASTPIN (-3525 4100) BN 5
J 0
(-3537 4108);
DISPLAY 0.489362 (-3537 4108);
PAINT GREEN (-3537 4108);
FORCEPROP 2 LAST CDS_LIB mstr_standard
J 0
(-3475 4100);
DISPLAY 0.723404 (-3475 4100);
PAINT MONO (-3475 4100);
DISPLAY INVISIBLE (-3475 4100);
FORCEPROP 1 LAST BODY_TYPE PLUMBING
J 0
(-3475 4150);
DISPLAY 0.872340 (-3475 4150);
PAINT GREEN (-3475 4150);
DISPLAY INVISIBLE (-3475 4150);
FORCEPROP 1 LAST HDL_TAP TRUE
J 0
(-3150 3975);
DISPLAY 0.872340 (-3150 3975);
DISPLAY INVISIBLE (-3150 3975);
FORCEPROP 1 LAST PATH I203
J 0
(-3477 4100);
DISPLAY 0.872340 (-3477 4100);
PAINT GREEN (-3477 4100);
DISPLAY INVISIBLE (-3477 4100);
FORCEADD TAP..1
(-3275 4050);
FORCEPROP 3 LASTPIN (-3325 4050) SIG_NAME M_K_CPU1_SA_DQS_DN<5>
J 0
(-3315 4060);
DISPLAY 0.659574 (-3315 4060);
PAINT MONO (-3315 4060);
DISPLAY INVISIBLE (-3315 4060);
FORCEPROP 1 LASTPIN (-3325 4050) BN 5
J 0
(-3337 4058);
DISPLAY 0.489362 (-3337 4058);
PAINT GREEN (-3337 4058);
FORCEPROP 2 LAST CDS_LIB mstr_standard
J 0
(-3275 4050);
DISPLAY 0.723404 (-3275 4050);
PAINT MONO (-3275 4050);
DISPLAY INVISIBLE (-3275 4050);
FORCEPROP 1 LAST BODY_TYPE PLUMBING
J 0
(-3275 4100);
DISPLAY 0.872340 (-3275 4100);
PAINT GREEN (-3275 4100);
DISPLAY INVISIBLE (-3275 4100);
FORCEPROP 1 LAST HDL_TAP TRUE
J 0
(-2950 3925);
DISPLAY 0.872340 (-2950 3925);
DISPLAY INVISIBLE (-2950 3925);
FORCEPROP 1 LAST PATH I204
J 0
(-3277 4050);
DISPLAY 0.872340 (-3277 4050);
PAINT GREEN (-3277 4050);
DISPLAY INVISIBLE (-3277 4050);
FORCEADD TAP..1
(-3275 3850);
FORCEPROP 3 LASTPIN (-3325 3850) SIG_NAME M_K_CPU1_SA_DQS_DN<3>
J 0
(-3315 3860);
DISPLAY 0.659574 (-3315 3860);
PAINT MONO (-3315 3860);
DISPLAY INVISIBLE (-3315 3860);
FORCEPROP 1 LASTPIN (-3325 3850) BN 3
J 0
(-3337 3858);
DISPLAY 0.489362 (-3337 3858);
PAINT GREEN (-3337 3858);
FORCEPROP 2 LAST CDS_LIB mstr_standard
J 0
(-3275 3850);
DISPLAY 0.723404 (-3275 3850);
PAINT MONO (-3275 3850);
DISPLAY INVISIBLE (-3275 3850);
FORCEPROP 1 LAST BODY_TYPE PLUMBING
J 0
(-3275 3900);
DISPLAY 0.872340 (-3275 3900);
PAINT GREEN (-3275 3900);
DISPLAY INVISIBLE (-3275 3900);
FORCEPROP 1 LAST HDL_TAP TRUE
J 0
(-2950 3725);
DISPLAY 0.872340 (-2950 3725);
DISPLAY INVISIBLE (-2950 3725);
FORCEPROP 1 LAST PATH I205
J 0
(-3277 3850);
DISPLAY 0.872340 (-3277 3850);
PAINT GREEN (-3277 3850);
DISPLAY INVISIBLE (-3277 3850);
FORCEADD TAP..1
(-3275 3950);
FORCEPROP 3 LASTPIN (-3325 3950) SIG_NAME M_K_CPU1_SA_DQS_DN<4>
J 0
(-3315 3960);
DISPLAY 0.659574 (-3315 3960);
PAINT MONO (-3315 3960);
DISPLAY INVISIBLE (-3315 3960);
FORCEPROP 1 LASTPIN (-3325 3950) BN 4
J 0
(-3337 3958);
DISPLAY 0.489362 (-3337 3958);
PAINT GREEN (-3337 3958);
FORCEPROP 2 LAST CDS_LIB mstr_standard
J 0
(-3275 3950);
DISPLAY 0.723404 (-3275 3950);
PAINT MONO (-3275 3950);
DISPLAY INVISIBLE (-3275 3950);
FORCEPROP 1 LAST BODY_TYPE PLUMBING
J 0
(-3275 4000);
DISPLAY 0.872340 (-3275 4000);
PAINT GREEN (-3275 4000);
DISPLAY INVISIBLE (-3275 4000);
FORCEPROP 1 LAST HDL_TAP TRUE
J 0
(-2950 3825);
DISPLAY 0.872340 (-2950 3825);
DISPLAY INVISIBLE (-2950 3825);
FORCEPROP 1 LAST PATH I206
J 0
(-3277 3950);
DISPLAY 0.872340 (-3277 3950);
PAINT GREEN (-3277 3950);
DISPLAY INVISIBLE (-3277 3950);
FORCEADD TAP..1
(-3475 4000);
FORCEPROP 3 LASTPIN (-3525 4000) SIG_NAME M_K_CPU1_SA_DQS_DP<4>
J 0
(-3515 4010);
DISPLAY 0.659574 (-3515 4010);
PAINT MONO (-3515 4010);
DISPLAY INVISIBLE (-3515 4010);
FORCEPROP 1 LASTPIN (-3525 4000) BN 4
J 0
(-3537 4008);
DISPLAY 0.489362 (-3537 4008);
PAINT GREEN (-3537 4008);
FORCEPROP 2 LAST CDS_LIB mstr_standard
J 0
(-3475 4000);
DISPLAY 0.723404 (-3475 4000);
PAINT MONO (-3475 4000);
DISPLAY INVISIBLE (-3475 4000);
FORCEPROP 1 LAST BODY_TYPE PLUMBING
J 0
(-3475 4050);
DISPLAY 0.872340 (-3475 4050);
PAINT GREEN (-3475 4050);
DISPLAY INVISIBLE (-3475 4050);
FORCEPROP 1 LAST HDL_TAP TRUE
J 0
(-3150 3875);
DISPLAY 0.872340 (-3150 3875);
DISPLAY INVISIBLE (-3150 3875);
FORCEPROP 1 LAST PATH I207
J 0
(-3477 4000);
DISPLAY 0.872340 (-3477 4000);
PAINT GREEN (-3477 4000);
DISPLAY INVISIBLE (-3477 4000);
FORCEADD TAP..1
(-3475 3900);
FORCEPROP 3 LASTPIN (-3525 3900) SIG_NAME M_K_CPU1_SA_DQS_DP<3>
J 0
(-3515 3910);
DISPLAY 0.659574 (-3515 3910);
PAINT MONO (-3515 3910);
DISPLAY INVISIBLE (-3515 3910);
FORCEPROP 1 LASTPIN (-3525 3900) BN 3
J 0
(-3537 3908);
DISPLAY 0.489362 (-3537 3908);
PAINT GREEN (-3537 3908);
FORCEPROP 2 LAST CDS_LIB mstr_standard
J 0
(-3475 3900);
DISPLAY 0.723404 (-3475 3900);
PAINT MONO (-3475 3900);
DISPLAY INVISIBLE (-3475 3900);
FORCEPROP 1 LAST BODY_TYPE PLUMBING
J 0
(-3475 3950);
DISPLAY 0.872340 (-3475 3950);
PAINT GREEN (-3475 3950);
DISPLAY INVISIBLE (-3475 3950);
FORCEPROP 1 LAST HDL_TAP TRUE
J 0
(-3150 3775);
DISPLAY 0.872340 (-3150 3775);
DISPLAY INVISIBLE (-3150 3775);
FORCEPROP 1 LAST PATH I208
J 0
(-3477 3900);
DISPLAY 0.872340 (-3477 3900);
PAINT GREEN (-3477 3900);
DISPLAY INVISIBLE (-3477 3900);
FORCEADD TAP..1
(-3275 3750);
FORCEPROP 3 LASTPIN (-3325 3750) SIG_NAME M_K_CPU1_SA_DQS_DN<2>
J 0
(-3315 3760);
DISPLAY 0.659574 (-3315 3760);
PAINT MONO (-3315 3760);
DISPLAY INVISIBLE (-3315 3760);
FORCEPROP 1 LASTPIN (-3325 3750) BN 2
J 0
(-3337 3758);
DISPLAY 0.489362 (-3337 3758);
PAINT GREEN (-3337 3758);
FORCEPROP 2 LAST CDS_LIB mstr_standard
J 0
(-3275 3750);
DISPLAY 0.723404 (-3275 3750);
PAINT MONO (-3275 3750);
DISPLAY INVISIBLE (-3275 3750);
FORCEPROP 1 LAST BODY_TYPE PLUMBING
J 0
(-3275 3800);
DISPLAY 0.872340 (-3275 3800);
PAINT GREEN (-3275 3800);
DISPLAY INVISIBLE (-3275 3800);
FORCEPROP 1 LAST HDL_TAP TRUE
J 0
(-2950 3625);
DISPLAY 0.872340 (-2950 3625);
DISPLAY INVISIBLE (-2950 3625);
FORCEPROP 1 LAST PATH I209
J 0
(-3277 3750);
DISPLAY 0.872340 (-3277 3750);
PAINT GREEN (-3277 3750);
DISPLAY INVISIBLE (-3277 3750);
FORCEADD OFFPAGE..1
(-8300 4975);
FORCEPROP 2 LAST $XR0 47 
J 0
(-8521 4975);
DISPLAY 0.638298 (-8521 4975);
PAINT MONO (-8521 4975);
FORCEPROP 2 LAST CDS_LIB mstr_standard
J 0
(-8300 4975);
DISPLAY 0.723404 (-8300 4975);
PAINT MONO (-8300 4975);
DISPLAY INVISIBLE (-8300 4975);
FORCEPROP 1 LAST OFFPAGE TRUE
J 0
(-7975 4850);
DISPLAY 0.872340 (-7975 4850);
PAINT GREEN (-7975 4850);
DISPLAY INVISIBLE (-7975 4850);
FORCEPROP 1 LAST COMMENT_BODY TRUE
J 0
(-8175 4875);
DISPLAY 0.872340 (-8175 4875);
PAINT GREEN (-8175 4875);
DISPLAY INVISIBLE (-8175 4875);
FORCEPROP 2 LAST PATH I21
J 0
(-8500 5025);
DISPLAY 1.021277 (-8500 5025);
DISPLAY INVISIBLE (-8500 5025);
FORCEADD TAP..1
(-3275 3650);
FORCEPROP 3 LASTPIN (-3325 3650) SIG_NAME M_K_CPU1_SA_DQS_DN<1>
J 0
(-3315 3660);
DISPLAY 0.659574 (-3315 3660);
PAINT MONO (-3315 3660);
DISPLAY INVISIBLE (-3315 3660);
FORCEPROP 1 LASTPIN (-3325 3650) BN 1
J 0
(-3337 3658);
DISPLAY 0.489362 (-3337 3658);
PAINT GREEN (-3337 3658);
FORCEPROP 2 LAST CDS_LIB mstr_standard
J 0
(-3275 3650);
DISPLAY 0.723404 (-3275 3650);
PAINT MONO (-3275 3650);
DISPLAY INVISIBLE (-3275 3650);
FORCEPROP 1 LAST BODY_TYPE PLUMBING
J 0
(-3275 3700);
DISPLAY 0.872340 (-3275 3700);
PAINT GREEN (-3275 3700);
DISPLAY INVISIBLE (-3275 3700);
FORCEPROP 1 LAST HDL_TAP TRUE
J 0
(-2950 3525);
DISPLAY 0.872340 (-2950 3525);
DISPLAY INVISIBLE (-2950 3525);
FORCEPROP 1 LAST PATH I210
J 0
(-3277 3650);
DISPLAY 0.872340 (-3277 3650);
PAINT GREEN (-3277 3650);
DISPLAY INVISIBLE (-3277 3650);
FORCEADD TAP..1
(-3475 3800);
FORCEPROP 3 LASTPIN (-3525 3800) SIG_NAME M_K_CPU1_SA_DQS_DP<2>
J 0
(-3515 3810);
DISPLAY 0.659574 (-3515 3810);
PAINT MONO (-3515 3810);
DISPLAY INVISIBLE (-3515 3810);
FORCEPROP 1 LASTPIN (-3525 3800) BN 2
J 0
(-3537 3808);
DISPLAY 0.489362 (-3537 3808);
PAINT GREEN (-3537 3808);
FORCEPROP 2 LAST CDS_LIB mstr_standard
J 0
(-3475 3800);
DISPLAY 0.723404 (-3475 3800);
PAINT MONO (-3475 3800);
DISPLAY INVISIBLE (-3475 3800);
FORCEPROP 1 LAST BODY_TYPE PLUMBING
J 0
(-3475 3850);
DISPLAY 0.872340 (-3475 3850);
PAINT GREEN (-3475 3850);
DISPLAY INVISIBLE (-3475 3850);
FORCEPROP 1 LAST HDL_TAP TRUE
J 0
(-3150 3675);
DISPLAY 0.872340 (-3150 3675);
DISPLAY INVISIBLE (-3150 3675);
FORCEPROP 1 LAST PATH I211
J 0
(-3477 3800);
DISPLAY 0.872340 (-3477 3800);
PAINT GREEN (-3477 3800);
DISPLAY INVISIBLE (-3477 3800);
FORCEADD TAP..1
(-3475 3700);
FORCEPROP 3 LASTPIN (-3525 3700) SIG_NAME M_K_CPU1_SA_DQS_DP<1>
J 0
(-3515 3710);
DISPLAY 0.659574 (-3515 3710);
PAINT MONO (-3515 3710);
DISPLAY INVISIBLE (-3515 3710);
FORCEPROP 1 LASTPIN (-3525 3700) BN 1
J 0
(-3537 3708);
DISPLAY 0.489362 (-3537 3708);
PAINT GREEN (-3537 3708);
FORCEPROP 2 LAST CDS_LIB mstr_standard
J 0
(-3475 3700);
DISPLAY 0.723404 (-3475 3700);
PAINT MONO (-3475 3700);
DISPLAY INVISIBLE (-3475 3700);
FORCEPROP 1 LAST BODY_TYPE PLUMBING
J 0
(-3475 3750);
DISPLAY 0.872340 (-3475 3750);
PAINT GREEN (-3475 3750);
DISPLAY INVISIBLE (-3475 3750);
FORCEPROP 1 LAST HDL_TAP TRUE
J 0
(-3150 3575);
DISPLAY 0.872340 (-3150 3575);
DISPLAY INVISIBLE (-3150 3575);
FORCEPROP 1 LAST PATH I212
J 0
(-3477 3700);
DISPLAY 0.872340 (-3477 3700);
PAINT GREEN (-3477 3700);
DISPLAY INVISIBLE (-3477 3700);
FORCEADD TAP..1
(-3475 3600);
FORCEPROP 3 LASTPIN (-3525 3600) SIG_NAME M_K_CPU1_SA_DQS_DP<0>
J 0
(-3515 3610);
DISPLAY 0.659574 (-3515 3610);
PAINT MONO (-3515 3610);
DISPLAY INVISIBLE (-3515 3610);
FORCEPROP 1 LASTPIN (-3525 3600) BN 0
J 0
(-3537 3608);
DISPLAY 0.489362 (-3537 3608);
PAINT GREEN (-3537 3608);
FORCEPROP 2 LAST CDS_LIB mstr_standard
J 0
(-3475 3600);
DISPLAY 0.723404 (-3475 3600);
PAINT MONO (-3475 3600);
DISPLAY INVISIBLE (-3475 3600);
FORCEPROP 1 LAST BODY_TYPE PLUMBING
J 0
(-3475 3650);
DISPLAY 0.872340 (-3475 3650);
PAINT GREEN (-3475 3650);
DISPLAY INVISIBLE (-3475 3650);
FORCEPROP 1 LAST HDL_TAP TRUE
J 0
(-3150 3475);
DISPLAY 0.872340 (-3150 3475);
DISPLAY INVISIBLE (-3150 3475);
FORCEPROP 1 LAST PATH I213
J 0
(-3477 3600);
DISPLAY 0.872340 (-3477 3600);
PAINT GREEN (-3477 3600);
DISPLAY INVISIBLE (-3477 3600);
FORCEADD TAP..1
(-3275 3550);
FORCEPROP 3 LASTPIN (-3325 3550) SIG_NAME M_K_CPU1_SA_DQS_DN<0>
J 0
(-3315 3560);
DISPLAY 0.659574 (-3315 3560);
PAINT MONO (-3315 3560);
DISPLAY INVISIBLE (-3315 3560);
FORCEPROP 1 LASTPIN (-3325 3550) BN 0
J 0
(-3337 3558);
DISPLAY 0.489362 (-3337 3558);
PAINT GREEN (-3337 3558);
FORCEPROP 2 LAST CDS_LIB mstr_standard
J 0
(-3275 3550);
DISPLAY 0.723404 (-3275 3550);
PAINT MONO (-3275 3550);
DISPLAY INVISIBLE (-3275 3550);
FORCEPROP 1 LAST BODY_TYPE PLUMBING
J 0
(-3275 3600);
DISPLAY 0.872340 (-3275 3600);
PAINT GREEN (-3275 3600);
DISPLAY INVISIBLE (-3275 3600);
FORCEPROP 1 LAST HDL_TAP TRUE
J 0
(-2950 3425);
DISPLAY 0.872340 (-2950 3425);
DISPLAY INVISIBLE (-2950 3425);
FORCEPROP 1 LAST PATH I214
J 0
(-3277 3550);
DISPLAY 0.872340 (-3277 3550);
PAINT GREEN (-3277 3550);
DISPLAY INVISIBLE (-3277 3550);
FORCEADD TAP..1
(-3275 3400);
FORCEPROP 3 LASTPIN (-3325 3400) SIG_NAME M_K_CPU1_SB_DQS_DN<9>
J 0
(-3315 3410);
DISPLAY 0.659574 (-3315 3410);
PAINT MONO (-3315 3410);
DISPLAY INVISIBLE (-3315 3410);
FORCEPROP 1 LASTPIN (-3325 3400) BN 9
J 0
(-3337 3408);
DISPLAY 0.489362 (-3337 3408);
PAINT GREEN (-3337 3408);
FORCEPROP 2 LAST CDS_LIB mstr_standard
J 0
(-3275 3400);
DISPLAY 0.723404 (-3275 3400);
PAINT MONO (-3275 3400);
DISPLAY INVISIBLE (-3275 3400);
FORCEPROP 1 LAST BODY_TYPE PLUMBING
J 0
(-3275 3450);
DISPLAY 0.872340 (-3275 3450);
PAINT GREEN (-3275 3450);
DISPLAY INVISIBLE (-3275 3450);
FORCEPROP 1 LAST HDL_TAP TRUE
J 0
(-2950 3275);
DISPLAY 0.872340 (-2950 3275);
DISPLAY INVISIBLE (-2950 3275);
FORCEPROP 1 LAST PATH I215
J 0
(-3277 3400);
DISPLAY 0.872340 (-3277 3400);
PAINT GREEN (-3277 3400);
DISPLAY INVISIBLE (-3277 3400);
FORCEADD TAP..1
(-3475 3450);
FORCEPROP 3 LASTPIN (-3525 3450) SIG_NAME M_K_CPU1_SB_DQS_DP<9>
J 0
(-3515 3460);
DISPLAY 0.659574 (-3515 3460);
PAINT MONO (-3515 3460);
DISPLAY INVISIBLE (-3515 3460);
FORCEPROP 1 LASTPIN (-3525 3450) BN 9
J 0
(-3537 3458);
DISPLAY 0.489362 (-3537 3458);
PAINT GREEN (-3537 3458);
FORCEPROP 2 LAST CDS_LIB mstr_standard
J 0
(-3475 3450);
DISPLAY 0.723404 (-3475 3450);
PAINT MONO (-3475 3450);
DISPLAY INVISIBLE (-3475 3450);
FORCEPROP 1 LAST BODY_TYPE PLUMBING
J 0
(-3475 3500);
DISPLAY 0.872340 (-3475 3500);
PAINT GREEN (-3475 3500);
DISPLAY INVISIBLE (-3475 3500);
FORCEPROP 1 LAST HDL_TAP TRUE
J 0
(-3150 3325);
DISPLAY 0.872340 (-3150 3325);
DISPLAY INVISIBLE (-3150 3325);
FORCEPROP 1 LAST PATH I216
J 0
(-3477 3450);
DISPLAY 0.872340 (-3477 3450);
PAINT GREEN (-3477 3450);
DISPLAY INVISIBLE (-3477 3450);
FORCEADD TAP..1
(-3475 3350);
FORCEPROP 3 LASTPIN (-3525 3350) SIG_NAME M_K_CPU1_SB_DQS_DP<8>
J 0
(-3515 3360);
DISPLAY 0.659574 (-3515 3360);
PAINT MONO (-3515 3360);
DISPLAY INVISIBLE (-3515 3360);
FORCEPROP 1 LASTPIN (-3525 3350) BN 8
J 0
(-3537 3358);
DISPLAY 0.489362 (-3537 3358);
PAINT GREEN (-3537 3358);
FORCEPROP 2 LAST CDS_LIB mstr_standard
J 0
(-3475 3350);
DISPLAY 0.723404 (-3475 3350);
PAINT MONO (-3475 3350);
DISPLAY INVISIBLE (-3475 3350);
FORCEPROP 1 LAST BODY_TYPE PLUMBING
J 0
(-3475 3400);
DISPLAY 0.872340 (-3475 3400);
PAINT GREEN (-3475 3400);
DISPLAY INVISIBLE (-3475 3400);
FORCEPROP 1 LAST HDL_TAP TRUE
J 0
(-3150 3225);
DISPLAY 0.872340 (-3150 3225);
DISPLAY INVISIBLE (-3150 3225);
FORCEPROP 1 LAST PATH I217
J 0
(-3477 3350);
DISPLAY 0.872340 (-3477 3350);
PAINT GREEN (-3477 3350);
DISPLAY INVISIBLE (-3477 3350);
FORCEADD TAP..1
(-3275 3200);
FORCEPROP 3 LASTPIN (-3325 3200) SIG_NAME M_K_CPU1_SB_DQS_DN<7>
J 0
(-3315 3210);
DISPLAY 0.659574 (-3315 3210);
PAINT MONO (-3315 3210);
DISPLAY INVISIBLE (-3315 3210);
FORCEPROP 1 LASTPIN (-3325 3200) BN 7
J 0
(-3337 3208);
DISPLAY 0.489362 (-3337 3208);
PAINT GREEN (-3337 3208);
FORCEPROP 2 LAST CDS_LIB mstr_standard
J 0
(-3275 3200);
DISPLAY 0.723404 (-3275 3200);
PAINT MONO (-3275 3200);
DISPLAY INVISIBLE (-3275 3200);
FORCEPROP 1 LAST BODY_TYPE PLUMBING
J 0
(-3275 3250);
DISPLAY 0.872340 (-3275 3250);
PAINT GREEN (-3275 3250);
DISPLAY INVISIBLE (-3275 3250);
FORCEPROP 1 LAST HDL_TAP TRUE
J 0
(-2950 3075);
DISPLAY 0.872340 (-2950 3075);
DISPLAY INVISIBLE (-2950 3075);
FORCEPROP 1 LAST PATH I218
J 0
(-3277 3200);
DISPLAY 0.872340 (-3277 3200);
PAINT GREEN (-3277 3200);
DISPLAY INVISIBLE (-3277 3200);
FORCEADD TAP..1
(-3275 3300);
FORCEPROP 3 LASTPIN (-3325 3300) SIG_NAME M_K_CPU1_SB_DQS_DN<8>
J 0
(-3315 3310);
DISPLAY 0.659574 (-3315 3310);
PAINT MONO (-3315 3310);
DISPLAY INVISIBLE (-3315 3310);
FORCEPROP 1 LASTPIN (-3325 3300) BN 8
J 0
(-3337 3308);
DISPLAY 0.489362 (-3337 3308);
PAINT GREEN (-3337 3308);
FORCEPROP 2 LAST CDS_LIB mstr_standard
J 0
(-3275 3300);
DISPLAY 0.723404 (-3275 3300);
PAINT MONO (-3275 3300);
DISPLAY INVISIBLE (-3275 3300);
FORCEPROP 1 LAST BODY_TYPE PLUMBING
J 0
(-3275 3350);
DISPLAY 0.872340 (-3275 3350);
PAINT GREEN (-3275 3350);
DISPLAY INVISIBLE (-3275 3350);
FORCEPROP 1 LAST HDL_TAP TRUE
J 0
(-2950 3175);
DISPLAY 0.872340 (-2950 3175);
DISPLAY INVISIBLE (-2950 3175);
FORCEPROP 1 LAST PATH I219
J 0
(-3277 3300);
DISPLAY 0.872340 (-3277 3300);
PAINT GREEN (-3277 3300);
DISPLAY INVISIBLE (-3277 3300);
FORCEADD SCONN288_DDR506112002KQ..1
(-6850 3575);
FORCEPROP 1 LAST LOCATION J99
J 0
(-7300 5650);
DISPLAY 0.468085 (-7300 5650);
PAINT SKYBLUE (-7300 5650);
FORCEPROP 0 LAST $SEC 1
J 0
(-7300 5800);
DISPLAY 0.680851 (-7300 5800);
PAINT MONO (-7300 5800);
DISPLAY INVISIBLE (-7300 5800);
FORCEPROP 2 LAST CDS_SEC 1
J 0
(-7300 5800);
DISPLAY 1.021277 (-7300 5800);
DISPLAY INVISIBLE (-7300 5800);
FORCEPROP 0 LASTPIN (-7450 2975) $PN 62
J 2
(-7460 2985);
DISPLAY 0.680851 (-7460 2985);
PAINT MONO (-7460 2985);
FORCEPROP 0 LASTPIN (-7450 5025) $PN 66
J 2
(-7460 5035);
DISPLAY 0.680851 (-7460 5035);
PAINT MONO (-7460 5035);
FORCEPROP 0 LASTPIN (-7450 4625) $PN 76
J 2
(-7460 4635);
DISPLAY 0.680851 (-7460 4635);
PAINT MONO (-7460 4635);
FORCEPROP 0 LASTPIN (-7450 5075) $PN 211
J 2
(-7460 5085);
DISPLAY 0.680851 (-7460 5085);
PAINT MONO (-7460 5085);
FORCEPROP 0 LASTPIN (-7450 4675) $PN 221
J 2
(-7460 4685);
DISPLAY 0.680851 (-7460 4685);
PAINT MONO (-7460 4685);
FORCEPROP 0 LASTPIN (-7450 5125) $PN 68
J 2
(-7460 5135);
DISPLAY 0.680851 (-7460 5135);
PAINT MONO (-7460 5135);
FORCEPROP 0 LASTPIN (-7450 4725) $PN 78
J 2
(-7460 4735);
DISPLAY 0.680851 (-7460 4735);
PAINT MONO (-7460 4735);
FORCEPROP 0 LASTPIN (-7450 5175) $PN 213
J 2
(-7460 5185);
DISPLAY 0.680851 (-7460 5185);
PAINT MONO (-7460 5185);
FORCEPROP 0 LASTPIN (-7450 4775) $PN 223
J 2
(-7460 4785);
DISPLAY 0.680851 (-7460 4785);
PAINT MONO (-7460 4785);
FORCEPROP 0 LASTPIN (-7450 5225) $PN 70
J 2
(-7460 5235);
DISPLAY 0.680851 (-7460 5235);
PAINT MONO (-7460 5235);
FORCEPROP 0 LASTPIN (-7450 4825) $PN 80
J 2
(-7460 4835);
DISPLAY 0.680851 (-7460 4835);
PAINT MONO (-7460 4835);
FORCEPROP 0 LASTPIN (-7450 5275) $PN 215
J 2
(-7460 5285);
DISPLAY 0.680851 (-7460 5285);
PAINT MONO (-7460 5285);
FORCEPROP 0 LASTPIN (-7450 4875) $PN 225
J 2
(-7460 4885);
DISPLAY 0.680851 (-7460 4885);
PAINT MONO (-7460 4885);
FORCEPROP 0 LASTPIN (-7450 5325) $PN 72
J 2
(-7460 5335);
DISPLAY 0.680851 (-7460 5335);
PAINT MONO (-7460 5335);
FORCEPROP 0 LASTPIN (-7450 4925) $PN 82
J 2
(-7460 4935);
DISPLAY 0.680851 (-7460 4935);
PAINT MONO (-7460 4935);
FORCEPROP 0 LASTPIN (-7450 3575) $PN 51
J 2
(-7460 3585);
DISPLAY 0.680851 (-7460 3585);
PAINT MONO (-7460 3585);
FORCEPROP 0 LASTPIN (-7450 3125) $PN 96
J 2
(-7460 3135);
DISPLAY 0.680851 (-7460 3135);
PAINT MONO (-7460 3135);
FORCEPROP 0 LASTPIN (-7450 3625) $PN 53
J 2
(-7460 3635);
DISPLAY 0.680851 (-7460 3635);
PAINT MONO (-7460 3635);
FORCEPROP 0 LASTPIN (-7450 3175) $PN 98
J 2
(-7460 3185);
DISPLAY 0.680851 (-7460 3185);
PAINT MONO (-7460 3185);
FORCEPROP 0 LASTPIN (-7450 3675) $PN 196
J 2
(-7460 3685);
DISPLAY 0.680851 (-7460 3685);
PAINT MONO (-7460 3685);
FORCEPROP 0 LASTPIN (-7450 3225) $PN 241
J 2
(-7460 3235);
DISPLAY 0.680851 (-7460 3235);
PAINT MONO (-7460 3235);
FORCEPROP 0 LASTPIN (-7450 3725) $PN 198
J 2
(-7460 3735);
DISPLAY 0.680851 (-7460 3735);
PAINT MONO (-7460 3735);
FORCEPROP 0 LASTPIN (-7450 3275) $PN 243
J 2
(-7460 3285);
DISPLAY 0.680851 (-7460 3285);
PAINT MONO (-7460 3285);
FORCEPROP 0 LASTPIN (-7450 3775) $PN 58
J 2
(-7460 3785);
DISPLAY 0.680851 (-7460 3785);
PAINT MONO (-7460 3785);
FORCEPROP 0 LASTPIN (-7450 3325) $PN 89
J 2
(-7460 3335);
DISPLAY 0.680851 (-7460 3335);
PAINT MONO (-7460 3335);
FORCEPROP 0 LASTPIN (-7450 3825) $PN 60
J 2
(-7460 3835);
DISPLAY 0.680851 (-7460 3835);
PAINT MONO (-7460 3835);
FORCEPROP 0 LASTPIN (-7450 3375) $PN 91
J 2
(-7460 3385);
DISPLAY 0.680851 (-7460 3385);
PAINT MONO (-7460 3385);
FORCEPROP 0 LASTPIN (-7450 3875) $PN 203
J 2
(-7460 3885);
DISPLAY 0.680851 (-7460 3885);
PAINT MONO (-7460 3885);
FORCEPROP 0 LASTPIN (-7450 3425) $PN 234
J 2
(-7460 3435);
DISPLAY 0.680851 (-7460 3435);
PAINT MONO (-7460 3435);
FORCEPROP 0 LASTPIN (-7450 3925) $PN 205
J 2
(-7460 3935);
DISPLAY 0.680851 (-7460 3935);
PAINT MONO (-7460 3935);
FORCEPROP 0 LASTPIN (-7450 3475) $PN 236
J 2
(-7460 3485);
DISPLAY 0.680851 (-7460 3485);
PAINT MONO (-7460 3485);
FORCEPROP 0 LASTPIN (-7450 4025) $PN 218
J 2
(-7460 4035);
DISPLAY 0.680851 (-7460 4035);
PAINT MONO (-7460 4035);
FORCEPROP 0 LASTPIN (-7450 4075) $PN 217
J 2
(-7460 4085);
DISPLAY 0.680851 (-7460 4085);
PAINT MONO (-7460 4085);
FORCEPROP 0 LASTPIN (-7450 4325) $PN 64
J 2
(-7460 4335);
DISPLAY 0.680851 (-7460 4335);
PAINT MONO (-7460 4335);
FORCEPROP 0 LASTPIN (-7450 4175) $PN 84
J 2
(-7460 4185);
DISPLAY 0.680851 (-7460 4185);
PAINT MONO (-7460 4185);
FORCEPROP 0 LASTPIN (-7450 4375) $PN 209
J 2
(-7460 4385);
DISPLAY 0.680851 (-7460 4385);
PAINT MONO (-7460 4385);
FORCEPROP 0 LASTPIN (-7450 4225) $PN 229
J 2
(-7460 4235);
DISPLAY 0.680851 (-7460 4235);
PAINT MONO (-7460 4235);
FORCEPROP 0 LASTPIN (-6250 3775) $PN 7
J 0
(-6240 3785);
DISPLAY 0.680851 (-6240 3785);
PAINT MONO (-6240 3785);
FORCEPROP 0 LASTPIN (-6250 2125) $PN 100
J 0
(-6240 2135);
DISPLAY 0.680851 (-6240 2135);
PAINT MONO (-6240 2135);
FORCEPROP 0 LASTPIN (-6250 3825) $PN 9
J 0
(-6240 3835);
DISPLAY 0.680851 (-6240 3835);
PAINT MONO (-6240 3835);
FORCEPROP 0 LASTPIN (-6250 2175) $PN 102
J 0
(-6240 2185);
DISPLAY 0.680851 (-6240 2185);
PAINT MONO (-6240 2185);
FORCEPROP 0 LASTPIN (-6250 3875) $PN 152
J 0
(-6240 3885);
DISPLAY 0.680851 (-6240 3885);
PAINT MONO (-6240 3885);
FORCEPROP 0 LASTPIN (-6250 2225) $PN 245
J 0
(-6240 2235);
DISPLAY 0.680851 (-6240 2235);
PAINT MONO (-6240 2235);
FORCEPROP 0 LASTPIN (-6250 3925) $PN 154
J 0
(-6240 3935);
DISPLAY 0.680851 (-6240 3935);
PAINT MONO (-6240 3935);
FORCEPROP 0 LASTPIN (-6250 2275) $PN 247
J 0
(-6240 2285);
DISPLAY 0.680851 (-6240 2285);
PAINT MONO (-6240 2285);
FORCEPROP 0 LASTPIN (-6250 3975) $PN 14
J 0
(-6240 3985);
DISPLAY 0.680851 (-6240 3985);
PAINT MONO (-6240 3985);
FORCEPROP 0 LASTPIN (-6250 2325) $PN 107
J 0
(-6240 2335);
DISPLAY 0.680851 (-6240 2335);
PAINT MONO (-6240 2335);
FORCEPROP 0 LASTPIN (-6250 4025) $PN 16
J 0
(-6240 4035);
DISPLAY 0.680851 (-6240 4035);
PAINT MONO (-6240 4035);
FORCEPROP 0 LASTPIN (-6250 2375) $PN 109
J 0
(-6240 2385);
DISPLAY 0.680851 (-6240 2385);
PAINT MONO (-6240 2385);
FORCEPROP 0 LASTPIN (-6250 4075) $PN 159
J 0
(-6240 4085);
DISPLAY 0.680851 (-6240 4085);
PAINT MONO (-6240 4085);
FORCEPROP 0 LASTPIN (-6250 2425) $PN 252
J 0
(-6240 2435);
DISPLAY 0.680851 (-6240 2435);
PAINT MONO (-6240 2435);
FORCEPROP 0 LASTPIN (-6250 4125) $PN 161
J 0
(-6240 4135);
DISPLAY 0.680851 (-6240 4135);
PAINT MONO (-6240 4135);
FORCEPROP 0 LASTPIN (-6250 2475) $PN 254
J 0
(-6240 2485);
DISPLAY 0.680851 (-6240 2485);
PAINT MONO (-6240 2485);
FORCEPROP 0 LASTPIN (-6250 4175) $PN 18
J 0
(-6240 4185);
DISPLAY 0.680851 (-6240 4185);
PAINT MONO (-6240 4185);
FORCEPROP 0 LASTPIN (-6250 2525) $PN 111
J 0
(-6240 2535);
DISPLAY 0.680851 (-6240 2535);
PAINT MONO (-6240 2535);
FORCEPROP 0 LASTPIN (-6250 4225) $PN 20
J 0
(-6240 4235);
DISPLAY 0.680851 (-6240 4235);
PAINT MONO (-6240 4235);
FORCEPROP 0 LASTPIN (-6250 2575) $PN 113
J 0
(-6240 2585);
DISPLAY 0.680851 (-6240 2585);
PAINT MONO (-6240 2585);
FORCEPROP 0 LASTPIN (-6250 4275) $PN 163
J 0
(-6240 4285);
DISPLAY 0.680851 (-6240 4285);
PAINT MONO (-6240 4285);
FORCEPROP 0 LASTPIN (-6250 2625) $PN 256
J 0
(-6240 2635);
DISPLAY 0.680851 (-6240 2635);
PAINT MONO (-6240 2635);
FORCEPROP 0 LASTPIN (-6250 4325) $PN 165
J 0
(-6240 4335);
DISPLAY 0.680851 (-6240 4335);
PAINT MONO (-6240 4335);
FORCEPROP 0 LASTPIN (-6250 2675) $PN 258
J 0
(-6240 2685);
DISPLAY 0.680851 (-6240 2685);
PAINT MONO (-6240 2685);
FORCEPROP 0 LASTPIN (-6250 4375) $PN 25
J 0
(-6240 4385);
DISPLAY 0.680851 (-6240 4385);
PAINT MONO (-6240 4385);
FORCEPROP 0 LASTPIN (-6250 2725) $PN 118
J 0
(-6240 2735);
DISPLAY 0.680851 (-6240 2735);
PAINT MONO (-6240 2735);
FORCEPROP 0 LASTPIN (-6250 4425) $PN 27
J 0
(-6240 4435);
DISPLAY 0.680851 (-6240 4435);
PAINT MONO (-6240 4435);
FORCEPROP 0 LASTPIN (-6250 2775) $PN 120
J 0
(-6240 2785);
DISPLAY 0.680851 (-6240 2785);
PAINT MONO (-6240 2785);
FORCEPROP 0 LASTPIN (-6250 4475) $PN 170
J 0
(-6240 4485);
DISPLAY 0.680851 (-6240 4485);
PAINT MONO (-6240 4485);
FORCEPROP 0 LASTPIN (-6250 2825) $PN 263
J 0
(-6240 2835);
DISPLAY 0.680851 (-6240 2835);
PAINT MONO (-6240 2835);
FORCEPROP 0 LASTPIN (-6250 4525) $PN 172
J 0
(-6240 4535);
DISPLAY 0.680851 (-6240 4535);
PAINT MONO (-6240 4535);
FORCEPROP 0 LASTPIN (-6250 2875) $PN 265
J 0
(-6240 2885);
DISPLAY 0.680851 (-6240 2885);
PAINT MONO (-6240 2885);
FORCEPROP 0 LASTPIN (-6250 4575) $PN 29
J 0
(-6240 4585);
DISPLAY 0.680851 (-6240 4585);
PAINT MONO (-6240 4585);
FORCEPROP 0 LASTPIN (-6250 2925) $PN 122
J 0
(-6240 2935);
DISPLAY 0.680851 (-6240 2935);
PAINT MONO (-6240 2935);
FORCEPROP 0 LASTPIN (-6250 4625) $PN 31
J 0
(-6240 4635);
DISPLAY 0.680851 (-6240 4635);
PAINT MONO (-6240 4635);
FORCEPROP 0 LASTPIN (-6250 2975) $PN 124
J 0
(-6240 2985);
DISPLAY 0.680851 (-6240 2985);
PAINT MONO (-6240 2985);
FORCEPROP 0 LASTPIN (-6250 4675) $PN 174
J 0
(-6240 4685);
DISPLAY 0.680851 (-6240 4685);
PAINT MONO (-6240 4685);
FORCEPROP 0 LASTPIN (-6250 3025) $PN 267
J 0
(-6240 3035);
DISPLAY 0.680851 (-6240 3035);
PAINT MONO (-6240 3035);
FORCEPROP 0 LASTPIN (-6250 4725) $PN 176
J 0
(-6240 4735);
DISPLAY 0.680851 (-6240 4735);
PAINT MONO (-6240 4735);
FORCEPROP 0 LASTPIN (-6250 3075) $PN 269
J 0
(-6240 3085);
DISPLAY 0.680851 (-6240 3085);
PAINT MONO (-6240 3085);
FORCEPROP 0 LASTPIN (-6250 4775) $PN 36
J 0
(-6240 4785);
DISPLAY 0.680851 (-6240 4785);
PAINT MONO (-6240 4785);
FORCEPROP 0 LASTPIN (-6250 3125) $PN 129
J 0
(-6240 3135);
DISPLAY 0.680851 (-6240 3135);
PAINT MONO (-6240 3135);
FORCEPROP 0 LASTPIN (-6250 4825) $PN 38
J 0
(-6240 4835);
DISPLAY 0.680851 (-6240 4835);
PAINT MONO (-6240 4835);
FORCEPROP 0 LASTPIN (-6250 3175) $PN 131
J 0
(-6240 3185);
DISPLAY 0.680851 (-6240 3185);
PAINT MONO (-6240 3185);
FORCEPROP 0 LASTPIN (-6250 4875) $PN 181
J 0
(-6240 4885);
DISPLAY 0.680851 (-6240 4885);
PAINT MONO (-6240 4885);
FORCEPROP 0 LASTPIN (-6250 3225) $PN 274
J 0
(-6240 3235);
DISPLAY 0.680851 (-6240 3235);
PAINT MONO (-6240 3235);
FORCEPROP 0 LASTPIN (-6250 4925) $PN 183
J 0
(-6240 4935);
DISPLAY 0.680851 (-6240 4935);
PAINT MONO (-6240 4935);
FORCEPROP 0 LASTPIN (-6250 3275) $PN 276
J 0
(-6240 3285);
DISPLAY 0.680851 (-6240 3285);
PAINT MONO (-6240 3285);
FORCEPROP 0 LASTPIN (-6250 4975) $PN 40
J 0
(-6240 4985);
DISPLAY 0.680851 (-6240 4985);
PAINT MONO (-6240 4985);
FORCEPROP 0 LASTPIN (-6250 3325) $PN 133
J 0
(-6240 3335);
DISPLAY 0.680851 (-6240 3335);
PAINT MONO (-6240 3335);
FORCEPROP 0 LASTPIN (-6250 5025) $PN 42
J 0
(-6240 5035);
DISPLAY 0.680851 (-6240 5035);
PAINT MONO (-6240 5035);
FORCEPROP 0 LASTPIN (-6250 3375) $PN 135
J 0
(-6240 3385);
DISPLAY 0.680851 (-6240 3385);
PAINT MONO (-6240 3385);
FORCEPROP 0 LASTPIN (-6250 5075) $PN 185
J 0
(-6240 5085);
DISPLAY 0.680851 (-6240 5085);
PAINT MONO (-6240 5085);
FORCEPROP 0 LASTPIN (-6250 3425) $PN 278
J 0
(-6240 3435);
DISPLAY 0.680851 (-6240 3435);
PAINT MONO (-6240 3435);
FORCEPROP 0 LASTPIN (-6250 5125) $PN 187
J 0
(-6240 5135);
DISPLAY 0.680851 (-6240 5135);
PAINT MONO (-6240 5135);
FORCEPROP 0 LASTPIN (-6250 3475) $PN 280
J 0
(-6240 3485);
DISPLAY 0.680851 (-6240 3485);
PAINT MONO (-6240 3485);
FORCEPROP 0 LASTPIN (-6250 5175) $PN 47
J 0
(-6240 5185);
DISPLAY 0.680851 (-6240 5185);
PAINT MONO (-6240 5185);
FORCEPROP 0 LASTPIN (-6250 3525) $PN 140
J 0
(-6240 3535);
DISPLAY 0.680851 (-6240 3535);
PAINT MONO (-6240 3535);
FORCEPROP 0 LASTPIN (-6250 5225) $PN 49
J 0
(-6240 5235);
DISPLAY 0.680851 (-6240 5235);
PAINT MONO (-6240 5235);
FORCEPROP 0 LASTPIN (-6250 3575) $PN 142
J 0
(-6240 3585);
DISPLAY 0.680851 (-6240 3585);
PAINT MONO (-6240 3585);
FORCEPROP 0 LASTPIN (-6250 5275) $PN 192
J 0
(-6240 5285);
DISPLAY 0.680851 (-6240 5285);
PAINT MONO (-6240 5285);
FORCEPROP 0 LASTPIN (-6250 3625) $PN 285
J 0
(-6240 3635);
DISPLAY 0.680851 (-6240 3635);
PAINT MONO (-6240 3635);
FORCEPROP 0 LASTPIN (-6250 5325) $PN 194
J 0
(-6240 5335);
DISPLAY 0.680851 (-6240 5335);
PAINT MONO (-6240 5335);
FORCEPROP 0 LASTPIN (-6250 3675) $PN 287
J 0
(-6240 3685);
DISPLAY 0.680851 (-6240 3685);
PAINT MONO (-6240 3685);
FORCEPROP 0 LASTPIN (-7450 2825) $PN 148
J 2
(-7460 2835);
DISPLAY 0.680851 (-7460 2835);
PAINT MONO (-7460 2835);
FORCEPROP 0 LASTPIN (-7450 2725) $PN 4
J 2
(-7460 2735);
DISPLAY 0.680851 (-7460 2735);
PAINT MONO (-7460 2735);
FORCEPROP 0 LASTPIN (-7450 2775) $PN 5
J 2
(-7460 2785);
DISPLAY 0.680851 (-7460 2785);
PAINT MONO (-7460 2785);
FORCEPROP 0 LASTPIN (-7450 1925) $PN 86
J 2
(-7460 1935);
DISPLAY 0.680851 (-7460 1935);
PAINT MONO (-7460 1935);
FORCEPROP 0 LASTPIN (-7450 1875) $PN 87
J 2
(-7460 1885);
DISPLAY 0.680851 (-7460 1885);
PAINT MONO (-7460 1885);
FORCEPROP 0 LASTPIN (-7450 4525) $PN 74
J 2
(-7460 4535);
DISPLAY 0.680851 (-7460 4535);
PAINT MONO (-7460 4535);
FORCEPROP 0 LASTPIN (-7450 4475) $PN 227
J 2
(-7460 4485);
DISPLAY 0.680851 (-7460 4485);
PAINT MONO (-7460 4485);
FORCEPROP 0 LASTPIN (-7450 2475) $PN 147
J 2
(-7460 2485);
DISPLAY 0.680851 (-7460 2485);
PAINT MONO (-7460 2485);
FORCEPROP 0 LASTPIN (-7450 3025) $PN 207
J 2
(-7460 3035);
DISPLAY 0.680851 (-7460 3035);
PAINT MONO (-7460 3035);
FORCEPROP 0 LASTPIN (-7450 2075) $PN 2
J 2
(-7460 2085);
DISPLAY 0.680851 (-7460 2085);
PAINT MONO (-7460 2085);
FORCEPROP 0 LASTPIN (-7450 2125) $PN 144
J 2
(-7460 2135);
DISPLAY 0.680851 (-7460 2135);
PAINT MONO (-7460 2135);
FORCEPROP 0 LASTPIN (-7450 2175) $PN 149
J 2
(-7460 2185);
DISPLAY 0.680851 (-7460 2185);
PAINT MONO (-7460 2185);
FORCEPROP 0 LASTPIN (-7450 2225) $PN 150
J 2
(-7460 2235);
DISPLAY 0.680851 (-7460 2235);
PAINT MONO (-7460 2235);
FORCEPROP 0 LASTPIN (-7450 2275) $PN 220
J 2
(-7460 2285);
DISPLAY 0.680851 (-7460 2285);
PAINT MONO (-7460 2285);
FORCEPROP 0 LASTPIN (-7450 2325) $PN 231
J 2
(-7460 2335);
DISPLAY 0.680851 (-7460 2335);
PAINT MONO (-7460 2335);
FORCEPROP 0 LASTPIN (-7450 2375) $PN 232
J 2
(-7460 2385);
DISPLAY 0.680851 (-7460 2385);
PAINT MONO (-7460 2385);
FORCEPROP 0 LASTPIN (-7450 2875) $PN 3
J 2
(-7460 2885);
DISPLAY 0.680851 (-7460 2885);
PAINT MONO (-7460 2885);
FORCEPROP 2 LAST PART_TYPE SMLF
J 0
(-7300 5750);
DISPLAY 1.021277 (-7300 5750);
FORCEPROP 1 LAST MATERIAL IO
J 0
(-7300 5500);
DISPLAY 0.468085 (-7300 5500);
PAINT SKYBLUE (-7300 5500);
FORCEPROP 2 LAST VALUE SCONN288_DDR506112002KQ
J 0
(-7300 5700);
DISPLAY 0.489362 (-7300 5700);
PAINT SKYBLUE (-7300 5700);
FORCEPROP 1 LAST PART_NUMBER DFHST8FS479
J 0
(-7300 5575);
DISPLAY 0.468085 (-7300 5575);
PAINT SKYBLUE (-7300 5575);
FORCEPROP 1 LAST CDS_LMAN_SYM_OUTLINE -450,1900,450,-1850
J 0
(-6850 3575);
DISPLAY 0.468085 (-6850 3575);
PAINT GREEN (-6850 3575);
DISPLAY INVISIBLE (-6850 3575);
FORCEPROP 1 LAST PATH I22
J 0
(-6850 3575);
DISPLAY 0.723404 (-6850 3575);
PAINT GREEN (-6850 3575);
DISPLAY INVISIBLE (-6850 3575);
FORCEPROP 1 LAST NEEDS_NO_SIZE TRUE
J 0
(-6850 3575);
DISPLAY 0.723404 (-6850 3575);
PAINT GREEN (-6850 3575);
DISPLAY INVISIBLE (-6850 3575);
FORCEPROP 2 LAST CDS_LIB pure_quanta
J 0
(-6850 3575);
DISPLAY INVISIBLE (-6850 3575);
FORCEADD TAP..1
(-3275 3100);
FORCEPROP 3 LASTPIN (-3325 3100) SIG_NAME M_K_CPU1_SB_DQS_DN<6>
J 0
(-3315 3110);
DISPLAY 0.659574 (-3315 3110);
PAINT MONO (-3315 3110);
DISPLAY INVISIBLE (-3315 3110);
FORCEPROP 1 LASTPIN (-3325 3100) BN 6
J 0
(-3337 3108);
DISPLAY 0.489362 (-3337 3108);
PAINT GREEN (-3337 3108);
FORCEPROP 2 LAST CDS_LIB mstr_standard
J 0
(-3275 3100);
DISPLAY 0.723404 (-3275 3100);
PAINT MONO (-3275 3100);
DISPLAY INVISIBLE (-3275 3100);
FORCEPROP 1 LAST BODY_TYPE PLUMBING
J 0
(-3275 3150);
DISPLAY 0.872340 (-3275 3150);
PAINT GREEN (-3275 3150);
DISPLAY INVISIBLE (-3275 3150);
FORCEPROP 1 LAST HDL_TAP TRUE
J 0
(-2950 2975);
DISPLAY 0.872340 (-2950 2975);
DISPLAY INVISIBLE (-2950 2975);
FORCEPROP 1 LAST PATH I220
J 0
(-3277 3100);
DISPLAY 0.872340 (-3277 3100);
PAINT GREEN (-3277 3100);
DISPLAY INVISIBLE (-3277 3100);
FORCEADD TAP..1
(-3475 3250);
FORCEPROP 3 LASTPIN (-3525 3250) SIG_NAME M_K_CPU1_SB_DQS_DP<7>
J 0
(-3515 3260);
DISPLAY 0.659574 (-3515 3260);
PAINT MONO (-3515 3260);
DISPLAY INVISIBLE (-3515 3260);
FORCEPROP 1 LASTPIN (-3525 3250) BN 7
J 0
(-3537 3258);
DISPLAY 0.489362 (-3537 3258);
PAINT GREEN (-3537 3258);
FORCEPROP 2 LAST CDS_LIB mstr_standard
J 0
(-3475 3250);
DISPLAY 0.723404 (-3475 3250);
PAINT MONO (-3475 3250);
DISPLAY INVISIBLE (-3475 3250);
FORCEPROP 1 LAST BODY_TYPE PLUMBING
J 0
(-3475 3300);
DISPLAY 0.872340 (-3475 3300);
PAINT GREEN (-3475 3300);
DISPLAY INVISIBLE (-3475 3300);
FORCEPROP 1 LAST HDL_TAP TRUE
J 0
(-3150 3125);
DISPLAY 0.872340 (-3150 3125);
DISPLAY INVISIBLE (-3150 3125);
FORCEPROP 1 LAST PATH I221
J 0
(-3477 3250);
DISPLAY 0.872340 (-3477 3250);
PAINT GREEN (-3477 3250);
DISPLAY INVISIBLE (-3477 3250);
FORCEADD TAP..1
(-3475 3150);
FORCEPROP 3 LASTPIN (-3525 3150) SIG_NAME M_K_CPU1_SB_DQS_DP<6>
J 0
(-3515 3160);
DISPLAY 0.659574 (-3515 3160);
PAINT MONO (-3515 3160);
DISPLAY INVISIBLE (-3515 3160);
FORCEPROP 1 LASTPIN (-3525 3150) BN 6
J 0
(-3537 3158);
DISPLAY 0.489362 (-3537 3158);
PAINT GREEN (-3537 3158);
FORCEPROP 2 LAST CDS_LIB mstr_standard
J 0
(-3475 3150);
DISPLAY 0.723404 (-3475 3150);
PAINT MONO (-3475 3150);
DISPLAY INVISIBLE (-3475 3150);
FORCEPROP 1 LAST BODY_TYPE PLUMBING
J 0
(-3475 3200);
DISPLAY 0.872340 (-3475 3200);
PAINT GREEN (-3475 3200);
DISPLAY INVISIBLE (-3475 3200);
FORCEPROP 1 LAST HDL_TAP TRUE
J 0
(-3150 3025);
DISPLAY 0.872340 (-3150 3025);
DISPLAY INVISIBLE (-3150 3025);
FORCEPROP 1 LAST PATH I222
J 0
(-3477 3150);
DISPLAY 0.872340 (-3477 3150);
PAINT GREEN (-3477 3150);
DISPLAY INVISIBLE (-3477 3150);
FORCEADD TAP..1
(-3275 3000);
FORCEPROP 3 LASTPIN (-3325 3000) SIG_NAME M_K_CPU1_SB_DQS_DN<5>
J 0
(-3315 3010);
DISPLAY 0.659574 (-3315 3010);
PAINT MONO (-3315 3010);
DISPLAY INVISIBLE (-3315 3010);
FORCEPROP 1 LASTPIN (-3325 3000) BN 5
J 0
(-3337 3008);
DISPLAY 0.489362 (-3337 3008);
PAINT GREEN (-3337 3008);
FORCEPROP 2 LAST CDS_LIB mstr_standard
J 0
(-3275 3000);
DISPLAY 0.723404 (-3275 3000);
PAINT MONO (-3275 3000);
DISPLAY INVISIBLE (-3275 3000);
FORCEPROP 1 LAST BODY_TYPE PLUMBING
J 0
(-3275 3050);
DISPLAY 0.872340 (-3275 3050);
PAINT GREEN (-3275 3050);
DISPLAY INVISIBLE (-3275 3050);
FORCEPROP 1 LAST HDL_TAP TRUE
J 0
(-2950 2875);
DISPLAY 0.872340 (-2950 2875);
DISPLAY INVISIBLE (-2950 2875);
FORCEPROP 1 LAST PATH I223
J 0
(-3277 3000);
DISPLAY 0.872340 (-3277 3000);
PAINT GREEN (-3277 3000);
DISPLAY INVISIBLE (-3277 3000);
FORCEADD TAP..1
(-3275 2900);
FORCEPROP 3 LASTPIN (-3325 2900) SIG_NAME M_K_CPU1_SB_DQS_DN<4>
J 0
(-3315 2910);
DISPLAY 0.659574 (-3315 2910);
PAINT MONO (-3315 2910);
DISPLAY INVISIBLE (-3315 2910);
FORCEPROP 1 LASTPIN (-3325 2900) BN 4
J 0
(-3337 2908);
DISPLAY 0.489362 (-3337 2908);
PAINT GREEN (-3337 2908);
FORCEPROP 2 LAST CDS_LIB mstr_standard
J 0
(-3275 2900);
DISPLAY 0.723404 (-3275 2900);
PAINT MONO (-3275 2900);
DISPLAY INVISIBLE (-3275 2900);
FORCEPROP 1 LAST BODY_TYPE PLUMBING
J 0
(-3275 2950);
DISPLAY 0.872340 (-3275 2950);
PAINT GREEN (-3275 2950);
DISPLAY INVISIBLE (-3275 2950);
FORCEPROP 1 LAST HDL_TAP TRUE
J 0
(-2950 2775);
DISPLAY 0.872340 (-2950 2775);
DISPLAY INVISIBLE (-2950 2775);
FORCEPROP 1 LAST PATH I224
J 0
(-3277 2900);
DISPLAY 0.872340 (-3277 2900);
PAINT GREEN (-3277 2900);
DISPLAY INVISIBLE (-3277 2900);
FORCEADD TAP..1
(-3475 2950);
FORCEPROP 3 LASTPIN (-3525 2950) SIG_NAME M_K_CPU1_SB_DQS_DP<4>
J 0
(-3515 2960);
DISPLAY 0.659574 (-3515 2960);
PAINT MONO (-3515 2960);
DISPLAY INVISIBLE (-3515 2960);
FORCEPROP 1 LASTPIN (-3525 2950) BN 4
J 0
(-3537 2958);
DISPLAY 0.489362 (-3537 2958);
PAINT GREEN (-3537 2958);
FORCEPROP 2 LAST CDS_LIB mstr_standard
J 0
(-3475 2950);
DISPLAY 0.723404 (-3475 2950);
PAINT MONO (-3475 2950);
DISPLAY INVISIBLE (-3475 2950);
FORCEPROP 1 LAST BODY_TYPE PLUMBING
J 0
(-3475 3000);
DISPLAY 0.872340 (-3475 3000);
PAINT GREEN (-3475 3000);
DISPLAY INVISIBLE (-3475 3000);
FORCEPROP 1 LAST HDL_TAP TRUE
J 0
(-3150 2825);
DISPLAY 0.872340 (-3150 2825);
DISPLAY INVISIBLE (-3150 2825);
FORCEPROP 1 LAST PATH I225
J 0
(-3477 2950);
DISPLAY 0.872340 (-3477 2950);
PAINT GREEN (-3477 2950);
DISPLAY INVISIBLE (-3477 2950);
FORCEADD TAP..1
(-3475 3050);
FORCEPROP 3 LASTPIN (-3525 3050) SIG_NAME M_K_CPU1_SB_DQS_DP<5>
J 0
(-3515 3060);
DISPLAY 0.659574 (-3515 3060);
PAINT MONO (-3515 3060);
DISPLAY INVISIBLE (-3515 3060);
FORCEPROP 1 LASTPIN (-3525 3050) BN 5
J 0
(-3537 3058);
DISPLAY 0.489362 (-3537 3058);
PAINT GREEN (-3537 3058);
FORCEPROP 2 LAST CDS_LIB mstr_standard
J 0
(-3475 3050);
DISPLAY 0.723404 (-3475 3050);
PAINT MONO (-3475 3050);
DISPLAY INVISIBLE (-3475 3050);
FORCEPROP 1 LAST BODY_TYPE PLUMBING
J 0
(-3475 3100);
DISPLAY 0.872340 (-3475 3100);
PAINT GREEN (-3475 3100);
DISPLAY INVISIBLE (-3475 3100);
FORCEPROP 1 LAST HDL_TAP TRUE
J 0
(-3150 2925);
DISPLAY 0.872340 (-3150 2925);
DISPLAY INVISIBLE (-3150 2925);
FORCEPROP 1 LAST PATH I226
J 0
(-3477 3050);
DISPLAY 0.872340 (-3477 3050);
PAINT GREEN (-3477 3050);
DISPLAY INVISIBLE (-3477 3050);
FORCEADD TAP..1
(-3475 2850);
FORCEPROP 3 LASTPIN (-3525 2850) SIG_NAME M_K_CPU1_SB_DQS_DP<3>
J 0
(-3515 2860);
DISPLAY 0.659574 (-3515 2860);
PAINT MONO (-3515 2860);
DISPLAY INVISIBLE (-3515 2860);
FORCEPROP 1 LASTPIN (-3525 2850) BN 3
J 0
(-3537 2858);
DISPLAY 0.489362 (-3537 2858);
PAINT GREEN (-3537 2858);
FORCEPROP 2 LAST CDS_LIB mstr_standard
J 0
(-3475 2850);
DISPLAY 0.723404 (-3475 2850);
PAINT MONO (-3475 2850);
DISPLAY INVISIBLE (-3475 2850);
FORCEPROP 1 LAST BODY_TYPE PLUMBING
J 0
(-3475 2900);
DISPLAY 0.872340 (-3475 2900);
PAINT GREEN (-3475 2900);
DISPLAY INVISIBLE (-3475 2900);
FORCEPROP 1 LAST HDL_TAP TRUE
J 0
(-3150 2725);
DISPLAY 0.872340 (-3150 2725);
DISPLAY INVISIBLE (-3150 2725);
FORCEPROP 1 LAST PATH I227
J 0
(-3477 2850);
DISPLAY 0.872340 (-3477 2850);
PAINT GREEN (-3477 2850);
DISPLAY INVISIBLE (-3477 2850);
FORCEADD TAP..1
(-3275 2700);
FORCEPROP 3 LASTPIN (-3325 2700) SIG_NAME M_K_CPU1_SB_DQS_DN<2>
J 0
(-3315 2710);
DISPLAY 0.659574 (-3315 2710);
PAINT MONO (-3315 2710);
DISPLAY INVISIBLE (-3315 2710);
FORCEPROP 1 LASTPIN (-3325 2700) BN 2
J 0
(-3337 2708);
DISPLAY 0.489362 (-3337 2708);
PAINT GREEN (-3337 2708);
FORCEPROP 2 LAST CDS_LIB mstr_standard
J 0
(-3275 2700);
DISPLAY 0.723404 (-3275 2700);
PAINT MONO (-3275 2700);
DISPLAY INVISIBLE (-3275 2700);
FORCEPROP 1 LAST BODY_TYPE PLUMBING
J 0
(-3275 2750);
DISPLAY 0.872340 (-3275 2750);
PAINT GREEN (-3275 2750);
DISPLAY INVISIBLE (-3275 2750);
FORCEPROP 1 LAST HDL_TAP TRUE
J 0
(-2950 2575);
DISPLAY 0.872340 (-2950 2575);
DISPLAY INVISIBLE (-2950 2575);
FORCEPROP 1 LAST PATH I228
J 0
(-3277 2700);
DISPLAY 0.872340 (-3277 2700);
PAINT GREEN (-3277 2700);
DISPLAY INVISIBLE (-3277 2700);
FORCEADD TAP..1
(-3275 2800);
FORCEPROP 3 LASTPIN (-3325 2800) SIG_NAME M_K_CPU1_SB_DQS_DN<3>
J 0
(-3315 2810);
DISPLAY 0.659574 (-3315 2810);
PAINT MONO (-3315 2810);
DISPLAY INVISIBLE (-3315 2810);
FORCEPROP 1 LASTPIN (-3325 2800) BN 3
J 0
(-3337 2808);
DISPLAY 0.489362 (-3337 2808);
PAINT GREEN (-3337 2808);
FORCEPROP 2 LAST CDS_LIB mstr_standard
J 0
(-3275 2800);
DISPLAY 0.723404 (-3275 2800);
PAINT MONO (-3275 2800);
DISPLAY INVISIBLE (-3275 2800);
FORCEPROP 1 LAST BODY_TYPE PLUMBING
J 0
(-3275 2850);
DISPLAY 0.872340 (-3275 2850);
PAINT GREEN (-3275 2850);
DISPLAY INVISIBLE (-3275 2850);
FORCEPROP 1 LAST HDL_TAP TRUE
J 0
(-2950 2675);
DISPLAY 0.872340 (-2950 2675);
DISPLAY INVISIBLE (-2950 2675);
FORCEPROP 1 LAST PATH I229
J 0
(-3277 2800);
DISPLAY 0.872340 (-3277 2800);
PAINT GREEN (-3277 2800);
DISPLAY INVISIBLE (-3277 2800);
FORCEADD TAP..1
R 2
(-7700 3125);
FORCEPROP 3 LASTPIN (-7650 3125) SIG_NAME M_K_CPU1_SB_CB<0>
J 0
(-7640 3135);
DISPLAY 0.659574 (-7640 3135);
PAINT MONO (-7640 3135);
DISPLAY INVISIBLE (-7640 3135);
FORCEPROP 1 LASTPIN (-7650 3125) BN 0
J 2
(-7638 3133);
DISPLAY 0.489362 (-7638 3133);
PAINT GREEN (-7638 3133);
FORCEPROP 2 LAST CDS_LIB mstr_standard
J 0
(-7700 3125);
DISPLAY 0.723404 (-7700 3125);
PAINT MONO (-7700 3125);
DISPLAY INVISIBLE (-7700 3125);
FORCEPROP 1 LAST BODY_TYPE PLUMBING
J 2
(-7700 3175);
DISPLAY 0.872340 (-7700 3175);
PAINT GREEN (-7700 3175);
DISPLAY INVISIBLE (-7700 3175);
FORCEPROP 1 LAST HDL_TAP TRUE
J 2
(-8025 3000);
DISPLAY 0.872340 (-8025 3000);
DISPLAY INVISIBLE (-8025 3000);
FORCEPROP 1 LAST PATH I23
J 2
(-7698 3125);
DISPLAY 0.872340 (-7698 3125);
PAINT GREEN (-7698 3125);
DISPLAY INVISIBLE (-7698 3125);
FORCEADD TAP..1
(-3275 2600);
FORCEPROP 3 LASTPIN (-3325 2600) SIG_NAME M_K_CPU1_SB_DQS_DN<1>
J 0
(-3315 2610);
DISPLAY 0.659574 (-3315 2610);
PAINT MONO (-3315 2610);
DISPLAY INVISIBLE (-3315 2610);
FORCEPROP 1 LASTPIN (-3325 2600) BN 1
J 0
(-3337 2608);
DISPLAY 0.489362 (-3337 2608);
PAINT GREEN (-3337 2608);
FORCEPROP 2 LAST CDS_LIB mstr_standard
J 0
(-3275 2600);
DISPLAY 0.723404 (-3275 2600);
PAINT MONO (-3275 2600);
DISPLAY INVISIBLE (-3275 2600);
FORCEPROP 1 LAST BODY_TYPE PLUMBING
J 0
(-3275 2650);
DISPLAY 0.872340 (-3275 2650);
PAINT GREEN (-3275 2650);
DISPLAY INVISIBLE (-3275 2650);
FORCEPROP 1 LAST HDL_TAP TRUE
J 0
(-2950 2475);
DISPLAY 0.872340 (-2950 2475);
DISPLAY INVISIBLE (-2950 2475);
FORCEPROP 1 LAST PATH I230
J 0
(-3277 2600);
DISPLAY 0.872340 (-3277 2600);
PAINT GREEN (-3277 2600);
DISPLAY INVISIBLE (-3277 2600);
FORCEADD TAP..1
(-3475 2750);
FORCEPROP 3 LASTPIN (-3525 2750) SIG_NAME M_K_CPU1_SB_DQS_DP<2>
J 0
(-3515 2760);
DISPLAY 0.659574 (-3515 2760);
PAINT MONO (-3515 2760);
DISPLAY INVISIBLE (-3515 2760);
FORCEPROP 1 LASTPIN (-3525 2750) BN 2
J 0
(-3537 2758);
DISPLAY 0.489362 (-3537 2758);
PAINT GREEN (-3537 2758);
FORCEPROP 2 LAST CDS_LIB mstr_standard
J 0
(-3475 2750);
DISPLAY 0.723404 (-3475 2750);
PAINT MONO (-3475 2750);
DISPLAY INVISIBLE (-3475 2750);
FORCEPROP 1 LAST BODY_TYPE PLUMBING
J 0
(-3475 2800);
DISPLAY 0.872340 (-3475 2800);
PAINT GREEN (-3475 2800);
DISPLAY INVISIBLE (-3475 2800);
FORCEPROP 1 LAST HDL_TAP TRUE
J 0
(-3150 2625);
DISPLAY 0.872340 (-3150 2625);
DISPLAY INVISIBLE (-3150 2625);
FORCEPROP 1 LAST PATH I231
J 0
(-3477 2750);
DISPLAY 0.872340 (-3477 2750);
PAINT GREEN (-3477 2750);
DISPLAY INVISIBLE (-3477 2750);
FORCEADD TAP..1
(-3475 2650);
FORCEPROP 3 LASTPIN (-3525 2650) SIG_NAME M_K_CPU1_SB_DQS_DP<1>
J 0
(-3515 2660);
DISPLAY 0.659574 (-3515 2660);
PAINT MONO (-3515 2660);
DISPLAY INVISIBLE (-3515 2660);
FORCEPROP 1 LASTPIN (-3525 2650) BN 1
J 0
(-3537 2658);
DISPLAY 0.489362 (-3537 2658);
PAINT GREEN (-3537 2658);
FORCEPROP 2 LAST CDS_LIB mstr_standard
J 0
(-3475 2650);
DISPLAY 0.723404 (-3475 2650);
PAINT MONO (-3475 2650);
DISPLAY INVISIBLE (-3475 2650);
FORCEPROP 1 LAST BODY_TYPE PLUMBING
J 0
(-3475 2700);
DISPLAY 0.872340 (-3475 2700);
PAINT GREEN (-3475 2700);
DISPLAY INVISIBLE (-3475 2700);
FORCEPROP 1 LAST HDL_TAP TRUE
J 0
(-3150 2525);
DISPLAY 0.872340 (-3150 2525);
DISPLAY INVISIBLE (-3150 2525);
FORCEPROP 1 LAST PATH I232
J 0
(-3477 2650);
DISPLAY 0.872340 (-3477 2650);
PAINT GREEN (-3477 2650);
DISPLAY INVISIBLE (-3477 2650);
FORCEADD TAP..1
(-3475 2550);
FORCEPROP 3 LASTPIN (-3525 2550) SIG_NAME M_K_CPU1_SB_DQS_DP<0>
J 0
(-3515 2560);
DISPLAY 0.659574 (-3515 2560);
PAINT MONO (-3515 2560);
DISPLAY INVISIBLE (-3515 2560);
FORCEPROP 1 LASTPIN (-3525 2550) BN 0
J 0
(-3537 2558);
DISPLAY 0.489362 (-3537 2558);
PAINT GREEN (-3537 2558);
FORCEPROP 2 LAST CDS_LIB mstr_standard
J 0
(-3475 2550);
DISPLAY 0.723404 (-3475 2550);
PAINT MONO (-3475 2550);
DISPLAY INVISIBLE (-3475 2550);
FORCEPROP 1 LAST BODY_TYPE PLUMBING
J 0
(-3475 2600);
DISPLAY 0.872340 (-3475 2600);
PAINT GREEN (-3475 2600);
DISPLAY INVISIBLE (-3475 2600);
FORCEPROP 1 LAST HDL_TAP TRUE
J 0
(-3150 2425);
DISPLAY 0.872340 (-3150 2425);
DISPLAY INVISIBLE (-3150 2425);
FORCEPROP 1 LAST PATH I233
J 0
(-3477 2550);
DISPLAY 0.872340 (-3477 2550);
PAINT GREEN (-3477 2550);
DISPLAY INVISIBLE (-3477 2550);
FORCEADD TAP..1
(-3275 2500);
FORCEPROP 3 LASTPIN (-3325 2500) SIG_NAME M_K_CPU1_SB_DQS_DN<0>
J 0
(-3315 2510);
DISPLAY 0.659574 (-3315 2510);
PAINT MONO (-3315 2510);
DISPLAY INVISIBLE (-3315 2510);
FORCEPROP 1 LASTPIN (-3325 2500) BN 0
J 0
(-3337 2508);
DISPLAY 0.489362 (-3337 2508);
PAINT GREEN (-3337 2508);
FORCEPROP 2 LAST CDS_LIB mstr_standard
J 0
(-3275 2500);
DISPLAY 0.723404 (-3275 2500);
PAINT MONO (-3275 2500);
DISPLAY INVISIBLE (-3275 2500);
FORCEPROP 1 LAST BODY_TYPE PLUMBING
J 0
(-3275 2550);
DISPLAY 0.872340 (-3275 2550);
PAINT GREEN (-3275 2550);
DISPLAY INVISIBLE (-3275 2550);
FORCEPROP 1 LAST HDL_TAP TRUE
J 0
(-2950 2375);
DISPLAY 0.872340 (-2950 2375);
DISPLAY INVISIBLE (-2950 2375);
FORCEPROP 1 LAST PATH I234
J 0
(-3277 2500);
DISPLAY 0.872340 (-3277 2500);
PAINT GREEN (-3277 2500);
DISPLAY INVISIBLE (-3277 2500);
FORCEADD SCONN288_DDR506112002KQ..2
(-4425 3500);
FORCEPROP 1 LAST LOCATION J99
J 0
(-5025 4825);
DISPLAY 0.468085 (-5025 4825);
PAINT SKYBLUE (-5025 4825);
FORCEPROP 0 LAST $SEC 2
J 0
(-4875 4975);
DISPLAY 0.680851 (-4875 4975);
PAINT MONO (-4875 4975);
DISPLAY INVISIBLE (-4875 4975);
FORCEPROP 0 LAST CDS_SEC 2
J 0
(-4875 4975);
DISPLAY 1.021277 (-4875 4975);
DISPLAY INVISIBLE (-4875 4975);
FORCEPROP 0 LASTPIN (-3675 3550) $PN 12
J 0
(-3665 3560);
DISPLAY 0.680851 (-3665 3560);
PAINT MONO (-3665 3560);
FORCEPROP 0 LASTPIN (-3675 3600) $PN 11
J 0
(-3665 3610);
DISPLAY 0.680851 (-3665 3610);
PAINT MONO (-3665 3610);
FORCEPROP 0 LASTPIN (-3675 2500) $PN 105
J 0
(-3665 2510);
DISPLAY 0.680851 (-3665 2510);
PAINT MONO (-3665 2510);
FORCEPROP 0 LASTPIN (-3675 2550) $PN 104
J 0
(-3665 2560);
DISPLAY 0.680851 (-3665 2560);
PAINT MONO (-3665 2560);
FORCEPROP 0 LASTPIN (-3675 3650) $PN 23
J 0
(-3665 3660);
DISPLAY 0.680851 (-3665 3660);
PAINT MONO (-3665 3660);
FORCEPROP 0 LASTPIN (-3675 3700) $PN 22
J 0
(-3665 3710);
DISPLAY 0.680851 (-3665 3710);
PAINT MONO (-3665 3710);
FORCEPROP 0 LASTPIN (-3675 2600) $PN 116
J 0
(-3665 2610);
DISPLAY 0.680851 (-3665 2610);
PAINT MONO (-3665 2610);
FORCEPROP 0 LASTPIN (-3675 2650) $PN 115
J 0
(-3665 2660);
DISPLAY 0.680851 (-3665 2660);
PAINT MONO (-3665 2660);
FORCEPROP 0 LASTPIN (-3675 3750) $PN 34
J 0
(-3665 3760);
DISPLAY 0.680851 (-3665 3760);
PAINT MONO (-3665 3760);
FORCEPROP 0 LASTPIN (-3675 3800) $PN 33
J 0
(-3665 3810);
DISPLAY 0.680851 (-3665 3810);
PAINT MONO (-3665 3810);
FORCEPROP 0 LASTPIN (-3675 2700) $PN 127
J 0
(-3665 2710);
DISPLAY 0.680851 (-3665 2710);
PAINT MONO (-3665 2710);
FORCEPROP 0 LASTPIN (-3675 2750) $PN 126
J 0
(-3665 2760);
DISPLAY 0.680851 (-3665 2760);
PAINT MONO (-3665 2760);
FORCEPROP 0 LASTPIN (-3675 3850) $PN 45
J 0
(-3665 3860);
DISPLAY 0.680851 (-3665 3860);
PAINT MONO (-3665 3860);
FORCEPROP 0 LASTPIN (-3675 3900) $PN 44
J 0
(-3665 3910);
DISPLAY 0.680851 (-3665 3910);
PAINT MONO (-3665 3910);
FORCEPROP 0 LASTPIN (-3675 2800) $PN 138
J 0
(-3665 2810);
DISPLAY 0.680851 (-3665 2810);
PAINT MONO (-3665 2810);
FORCEPROP 0 LASTPIN (-3675 2850) $PN 137
J 0
(-3665 2860);
DISPLAY 0.680851 (-3665 2860);
PAINT MONO (-3665 2860);
FORCEPROP 0 LASTPIN (-3675 3950) $PN 56
J 0
(-3665 3960);
DISPLAY 0.680851 (-3665 3960);
PAINT MONO (-3665 3960);
FORCEPROP 0 LASTPIN (-3675 4000) $PN 55
J 0
(-3665 4010);
DISPLAY 0.680851 (-3665 4010);
PAINT MONO (-3665 4010);
FORCEPROP 0 LASTPIN (-3675 2900) $PN 238
J 0
(-3665 2910);
DISPLAY 0.680851 (-3665 2910);
PAINT MONO (-3665 2910);
FORCEPROP 0 LASTPIN (-3675 2950) $PN 239
J 0
(-3665 2960);
DISPLAY 0.680851 (-3665 2960);
PAINT MONO (-3665 2960);
FORCEPROP 0 LASTPIN (-3675 4050) $PN 156
J 0
(-3665 4060);
DISPLAY 0.680851 (-3665 4060);
PAINT MONO (-3665 4060);
FORCEPROP 0 LASTPIN (-3675 4100) $PN 157
J 0
(-3665 4110);
DISPLAY 0.680851 (-3665 4110);
PAINT MONO (-3665 4110);
FORCEPROP 0 LASTPIN (-3675 3000) $PN 249
J 0
(-3665 3010);
DISPLAY 0.680851 (-3665 3010);
PAINT MONO (-3665 3010);
FORCEPROP 0 LASTPIN (-3675 3050) $PN 250
J 0
(-3665 3060);
DISPLAY 0.680851 (-3665 3060);
PAINT MONO (-3665 3060);
FORCEPROP 0 LASTPIN (-3675 4150) $PN 167
J 0
(-3665 4160);
DISPLAY 0.680851 (-3665 4160);
PAINT MONO (-3665 4160);
FORCEPROP 0 LASTPIN (-3675 4200) $PN 168
J 0
(-3665 4210);
DISPLAY 0.680851 (-3665 4210);
PAINT MONO (-3665 4210);
FORCEPROP 0 LASTPIN (-3675 3100) $PN 260
J 0
(-3665 3110);
DISPLAY 0.680851 (-3665 3110);
PAINT MONO (-3665 3110);
FORCEPROP 0 LASTPIN (-3675 3150) $PN 261
J 0
(-3665 3160);
DISPLAY 0.680851 (-3665 3160);
PAINT MONO (-3665 3160);
FORCEPROP 0 LASTPIN (-3675 4250) $PN 178
J 0
(-3665 4260);
DISPLAY 0.680851 (-3665 4260);
PAINT MONO (-3665 4260);
FORCEPROP 0 LASTPIN (-3675 4300) $PN 179
J 0
(-3665 4310);
DISPLAY 0.680851 (-3665 4310);
PAINT MONO (-3665 4310);
FORCEPROP 0 LASTPIN (-3675 3200) $PN 271
J 0
(-3665 3210);
DISPLAY 0.680851 (-3665 3210);
PAINT MONO (-3665 3210);
FORCEPROP 0 LASTPIN (-3675 3250) $PN 272
J 0
(-3665 3260);
DISPLAY 0.680851 (-3665 3260);
PAINT MONO (-3665 3260);
FORCEPROP 0 LASTPIN (-3675 4350) $PN 189
J 0
(-3665 4360);
DISPLAY 0.680851 (-3665 4360);
PAINT MONO (-3665 4360);
FORCEPROP 0 LASTPIN (-3675 4400) $PN 190
J 0
(-3665 4410);
DISPLAY 0.680851 (-3665 4410);
PAINT MONO (-3665 4410);
FORCEPROP 0 LASTPIN (-3675 3300) $PN 282
J 0
(-3665 3310);
DISPLAY 0.680851 (-3665 3310);
PAINT MONO (-3665 3310);
FORCEPROP 0 LASTPIN (-3675 3350) $PN 283
J 0
(-3665 3360);
DISPLAY 0.680851 (-3665 3360);
PAINT MONO (-3665 3360);
FORCEPROP 0 LASTPIN (-3675 4450) $PN 200
J 0
(-3665 4460);
DISPLAY 0.680851 (-3665 4460);
PAINT MONO (-3665 4460);
FORCEPROP 0 LASTPIN (-3675 4500) $PN 201
J 0
(-3665 4510);
DISPLAY 0.680851 (-3665 4510);
PAINT MONO (-3665 4510);
FORCEPROP 0 LASTPIN (-3675 3400) $PN 94
J 0
(-3665 3410);
DISPLAY 0.680851 (-3665 3410);
PAINT MONO (-3665 3410);
FORCEPROP 0 LASTPIN (-3675 3450) $PN 93
J 0
(-3665 3460);
DISPLAY 0.680851 (-3665 3460);
PAINT MONO (-3665 3460);
FORCEPROP 1 LAST MATERIAL IO
J 0
(-5025 4675);
DISPLAY 0.468085 (-5025 4675);
PAINT SKYBLUE (-5025 4675);
FORCEPROP 2 LAST VALUE SCONN288_DDR506112002KQ
J 0
(-4875 4875);
DISPLAY 0.489362 (-4875 4875);
PAINT SKYBLUE (-4875 4875);
FORCEPROP 2 LAST PART_TYPE SMLF
J 0
(-4875 4925);
DISPLAY 1.021277 (-4875 4925);
FORCEPROP 1 LAST PART_NUMBER DFHST8FS479
J 0
(-5025 4750);
DISPLAY 0.468085 (-5025 4750);
PAINT SKYBLUE (-5025 4750);
FORCEPROP 1 LAST CDS_LMAN_SYM_OUTLINE -600,1150,600,-1150
J 0
(-4425 3500);
DISPLAY 0.468085 (-4425 3500);
PAINT GREEN (-4425 3500);
DISPLAY INVISIBLE (-4425 3500);
FORCEPROP 1 LAST PATH I235
J 0
(-4425 3500);
DISPLAY 0.723404 (-4425 3500);
PAINT GREEN (-4425 3500);
DISPLAY INVISIBLE (-4425 3500);
FORCEPROP 1 LAST NEEDS_NO_SIZE TRUE
J 0
(-4425 3500);
DISPLAY 0.723404 (-4425 3500);
PAINT GREEN (-4425 3500);
DISPLAY INVISIBLE (-4425 3500);
FORCEPROP 2 LAST CDS_LIB pure_quanta
J 0
(-4425 3500);
DISPLAY INVISIBLE (-4425 3500);
FORCEADD GND..1
(-2850 5475);
FORCEPROP 3 LASTPIN (-2850 5525) SIG_NAME GND\g
J 0
(-2840 5535);
DISPLAY 0.659574 (-2840 5535);
PAINT MONO (-2840 5535);
DISPLAY INVISIBLE (-2840 5535);
FORCEPROP 1 LAST SIZE 1B
J 0
(-2775 5425);
DISPLAY 0.723404 (-2775 5425);
PAINT GREEN (-2775 5425);
DISPLAY INVISIBLE (-2775 5425);
FORCEPROP 2 LAST BOM_COST MEM
J 0
(-2825 5600);
DISPLAY 0.659574 (-2825 5600);
DISPLAY INVISIBLE (-2825 5600);
FORCEPROP 2 LAST CDS_LIB pure_quanta_power
J 0
(-2850 5475);
DISPLAY INVISIBLE (-2850 5475);
FORCEPROP 1 LAST PATH I236
J 0
(-2775 5475);
DISPLAY 0.872340 (-2775 5475);
PAINT AQUA (-2775 5475);
DISPLAY INVISIBLE (-2775 5475);
FORCEPROP 2 LAST ROOM MEM_EFGH_DECOUPLING_CAPS
J 0
(-2825 5550);
DISPLAY 0.659574 (-2825 5550);
PAINT RED (-2825 5550);
DISPLAY INVISIBLE (-2825 5550);
FORCEPROP 1 LAST HDL_POWER GND
J 0
(-2850 5625);
DISPLAY 0.723404 (-2850 5625);
PAINT GREEN (-2850 5625);
DISPLAY INVISIBLE (-2850 5625);
FORCEADD Q_CAP..1
R 2
(-2850 5825);
FORCEPROP 1 LAST LOCATION C546
J 2
(-2900 5925);
DISPLAY 0.489362 (-2900 5925);
PAINT SKYBLUE (-2900 5925);
FORCEPROP 0 LAST $SEC 1
J 0
(-2900 5975);
DISPLAY 0.680851 (-2900 5975);
PAINT MONO (-2900 5975);
DISPLAY INVISIBLE (-2900 5975);
FORCEPROP 0 LAST CDS_SEC 1
J 0
(-2900 5975);
DISPLAY 0.680851 (-2900 5975);
DISPLAY INVISIBLE (-2900 5975);
FORCEPROP 1 LASTPIN (-2850 5925) $PN 1
J 2
(-2860 5905);
DISPLAY 0.489362 (-2860 5905);
PAINT MONO (-2860 5905);
FORCEPROP 1 LASTPIN (-2850 5725) $PN 2
J 2
(-2860 5705);
DISPLAY 0.489362 (-2860 5705);
PAINT MONO (-2860 5705);
FORCEPROP 1 LAST MATERIAL X6S
J 2
(-2900 5725);
DISPLAY 0.489362 (-2900 5725);
PAINT SKYBLUE (-2900 5725);
FORCEPROP 1 LAST TOLERANCE 10%
J 2
(-2900 5775);
DISPLAY 0.489362 (-2900 5775);
PAINT SKYBLUE (-2900 5775);
FORCEPROP 1 LAST VALUE 10UF
J 2
(-2900 5875);
DISPLAY 0.489362 (-2900 5875);
PAINT SKYBLUE (-2900 5875);
FORCEPROP 1 LAST PART_NUMBER CH6104KEA00
J 2
(-2900 5675);
DISPLAY 0.489362 (-2900 5675);
PAINT SKYBLUE (-2900 5675);
FORCEPROP 1 LAST VOLTAGE 25V
J 2
(-2900 5825);
DISPLAY 0.489362 (-2900 5825);
PAINT SKYBLUE (-2900 5825);
FORCEPROP 1 LAST PACK_TYPE C0805
J 2
(-2900 5625);
DISPLAY 0.489362 (-2900 5625);
PAINT SKYBLUE (-2900 5625);
FORCEPROP 2 LAST CDS_LIB pure_quanta
J 0
(-2850 5825);
DISPLAY INVISIBLE (-2850 5825);
FORCEPROP 0 LAST BOM_COST MEM
J 2
(-2905 5970);
DISPLAY 0.595745 (-2905 5970);
PAINT MONO (-2905 5970);
DISPLAY INVISIBLE (-2905 5970);
FORCEPROP 1 LAST PATH I237
J 2
(-2900 5975);
DISPLAY 0.978723 (-2900 5975);
PAINT WHITE (-2900 5975);
DISPLAY INVISIBLE (-2900 5975);
FORCEPROP 0 LAST ROOM MEM_CH_A_CPU0_DIMM1
J 2
(-2905 5970);
DISPLAY 0.595745 (-2905 5970);
PAINT RED (-2905 5970);
DISPLAY INVISIBLE (-2905 5970);
FORCEADD Q_CAP..1
R 2
(-2275 5825);
FORCEPROP 1 LAST LOCATION C547
J 2
(-2325 5925);
DISPLAY 0.489362 (-2325 5925);
PAINT SKYBLUE (-2325 5925);
FORCEPROP 0 LAST $SEC 1
J 0
(-2325 5975);
DISPLAY 0.680851 (-2325 5975);
PAINT MONO (-2325 5975);
DISPLAY INVISIBLE (-2325 5975);
FORCEPROP 0 LAST CDS_SEC 1
J 0
(-2325 5975);
DISPLAY 0.680851 (-2325 5975);
DISPLAY INVISIBLE (-2325 5975);
FORCEPROP 1 LASTPIN (-2275 5925) $PN 1
J 2
(-2285 5905);
DISPLAY 0.489362 (-2285 5905);
PAINT MONO (-2285 5905);
FORCEPROP 1 LASTPIN (-2275 5725) $PN 2
J 2
(-2285 5705);
DISPLAY 0.489362 (-2285 5705);
PAINT MONO (-2285 5705);
FORCEPROP 1 LAST MATERIAL X6S
J 2
(-2325 5725);
DISPLAY 0.489362 (-2325 5725);
PAINT SKYBLUE (-2325 5725);
FORCEPROP 1 LAST TOLERANCE 10%
J 2
(-2325 5775);
DISPLAY 0.489362 (-2325 5775);
PAINT SKYBLUE (-2325 5775);
FORCEPROP 1 LAST VALUE 10UF
J 2
(-2325 5875);
DISPLAY 0.489362 (-2325 5875);
PAINT SKYBLUE (-2325 5875);
FORCEPROP 1 LAST PART_NUMBER CH6104KEA00
J 2
(-2325 5675);
DISPLAY 0.489362 (-2325 5675);
PAINT SKYBLUE (-2325 5675);
FORCEPROP 1 LAST VOLTAGE 25V
J 2
(-2325 5825);
DISPLAY 0.489362 (-2325 5825);
PAINT SKYBLUE (-2325 5825);
FORCEPROP 1 LAST PACK_TYPE C0805
J 2
(-2325 5625);
DISPLAY 0.489362 (-2325 5625);
PAINT SKYBLUE (-2325 5625);
FORCEPROP 2 LAST CDS_LIB pure_quanta
J 0
(-2275 5825);
DISPLAY INVISIBLE (-2275 5825);
FORCEPROP 0 LAST BOM_COST MEM
J 2
(-2330 5970);
DISPLAY 0.595745 (-2330 5970);
PAINT MONO (-2330 5970);
DISPLAY INVISIBLE (-2330 5970);
FORCEPROP 1 LAST PATH I238
J 2
(-2325 5975);
DISPLAY 0.978723 (-2325 5975);
PAINT WHITE (-2325 5975);
DISPLAY INVISIBLE (-2325 5975);
FORCEPROP 0 LAST ROOM MEM_CH_A_CPU0_DIMM1
J 2
(-2330 5970);
DISPLAY 0.595745 (-2330 5970);
PAINT RED (-2330 5970);
DISPLAY INVISIBLE (-2330 5970);
FORCEADD UNIVERSAL_POWER..1
(-2850 6150);
FORCEPROP 3 LASTPIN (-2850 6100) SIG_NAME P12V_MEM_1\g
J 0
(-2840 6110);
DISPLAY 0.659574 (-2840 6110);
PAINT MONO (-2840 6110);
DISPLAY INVISIBLE (-2840 6110);
FORCEPROP 1 LAST HDL_POWER P12V_MEM_1
J 1
(-2850 6200);
DISPLAY 0.489362 (-2850 6200);
PAINT GREEN (-2850 6200);
FORCEPROP 2 LAST CDS_LIB pure_quanta_power
J 0
(-2850 6150);
DISPLAY INVISIBLE (-2850 6150);
FORCEPROP 1 LAST PATH I239
J 0
(-2800 6175);
DISPLAY 0.872340 (-2800 6175);
PAINT AQUA (-2800 6175);
DISPLAY INVISIBLE (-2800 6175);
FORCEADD TAP..1
R 2
(-7700 3175);
FORCEPROP 3 LASTPIN (-7650 3175) SIG_NAME M_K_CPU1_SB_CB<1>
J 0
(-7640 3185);
DISPLAY 0.659574 (-7640 3185);
PAINT MONO (-7640 3185);
DISPLAY INVISIBLE (-7640 3185);
FORCEPROP 1 LASTPIN (-7650 3175) BN 1
J 2
(-7638 3183);
DISPLAY 0.489362 (-7638 3183);
PAINT GREEN (-7638 3183);
FORCEPROP 2 LAST CDS_LIB mstr_standard
J 0
(-7700 3175);
DISPLAY 0.723404 (-7700 3175);
PAINT MONO (-7700 3175);
DISPLAY INVISIBLE (-7700 3175);
FORCEPROP 1 LAST BODY_TYPE PLUMBING
J 2
(-7700 3225);
DISPLAY 0.872340 (-7700 3225);
PAINT GREEN (-7700 3225);
DISPLAY INVISIBLE (-7700 3225);
FORCEPROP 1 LAST HDL_TAP TRUE
J 2
(-8025 3050);
DISPLAY 0.872340 (-8025 3050);
DISPLAY INVISIBLE (-8025 3050);
FORCEPROP 1 LAST PATH I24
J 2
(-7698 3175);
DISPLAY 0.872340 (-7698 3175);
PAINT GREEN (-7698 3175);
DISPLAY INVISIBLE (-7698 3175);
FORCEADD OFFPAGE..1
(-8350 2625);
FORCEPROP 2 LAST $XR5 108 
J 0
(-9202 2625);
DISPLAY 0.638298 (-9202 2625);
PAINT MONO (-9202 2625);
FORCEPROP 2 LAST $XR4 106 
J 0
(-9082 2625);
DISPLAY 0.638298 (-9082 2625);
PAINT MONO (-9082 2625);
FORCEPROP 2 LAST $XR3 105 
J 0
(-8962 2625);
DISPLAY 0.638298 (-8962 2625);
PAINT MONO (-8962 2625);
FORCEPROP 2 LAST $XR2 104 
J 0
(-8842 2625);
DISPLAY 0.638298 (-8842 2625);
PAINT MONO (-8842 2625);
FORCEPROP 2 LAST $XR1 103 
J 0
(-8722 2625);
DISPLAY 0.638298 (-8722 2625);
PAINT MONO (-8722 2625);
FORCEPROP 2 LAST $XR0 136 
J 0
(-8602 2625);
DISPLAY 0.638298 (-8602 2625);
PAINT MONO (-8602 2625);
FORCEPROP 2 LAST PATH I240
J 0
(-8625 2675);
DISPLAY 0.680851 (-8625 2675);
DISPLAY INVISIBLE (-8625 2675);
FORCEPROP 2 LAST CDS_LIB mstr_standard
J 0
(-8350 2625);
DISPLAY 0.808511 (-8350 2625);
DISPLAY INVISIBLE (-8350 2625);
FORCEPROP 1 LAST OFFPAGE TRUE
J 0
(-8025 2500);
DISPLAY 0.872340 (-8025 2500);
PAINT GREEN (-8025 2500);
DISPLAY INVISIBLE (-8025 2500);
FORCEPROP 1 LAST COMMENT_BODY TRUE
J 0
(-8225 2525);
DISPLAY 0.872340 (-8225 2525);
PAINT GREEN (-8225 2525);
DISPLAY INVISIBLE (-8225 2525);
FORCEADD Q_RES..1
(-7750 2625);
FORCEPROP 1 LAST $LOCATION R1590
J 0
(-7800 2650);
DISPLAY 0.510638 (-7800 2650);
PAINT SKYBLUE (-7800 2650);
FORCEPROP 0 LAST CDS_LOCATION R1590
J 0
(-7800 2725);
DISPLAY 0.680851 (-7800 2725);
DISPLAY INVISIBLE (-7800 2725);
FORCEPROP 0 LAST $SEC 1
J 0
(-7800 2725);
DISPLAY 0.680851 (-7800 2725);
PAINT MONO (-7800 2725);
DISPLAY INVISIBLE (-7800 2725);
FORCEPROP 0 LAST CDS_SEC 1
J 0
(-7800 2725);
DISPLAY 0.680851 (-7800 2725);
DISPLAY INVISIBLE (-7800 2725);
FORCEPROP 1 LASTPIN (-7850 2625) $PN 1
J 0
(-7838 2637);
DISPLAY 0.787234 (-7838 2637);
PAINT MONO (-7838 2637);
FORCEPROP 1 LASTPIN (-7650 2625) $PN 2
J 0
(-7688 2637);
DISPLAY 0.787234 (-7688 2637);
PAINT MONO (-7688 2637);
FORCEPROP 1 LAST VALUE 49.9
J 2
(-7575 2675);
DISPLAY 0.510638 (-7575 2675);
PAINT SKYBLUE (-7575 2675);
FORCEPROP 2 LAST CDS_LIB pure_quanta
J 0
(-7750 2625);
DISPLAY INVISIBLE (-7750 2625);
FORCEPROP 1 LAST PATH I241
J 0
(-7800 2775);
DISPLAY 0.978723 (-7800 2775);
PAINT WHITE (-7800 2775);
DISPLAY INVISIBLE (-7800 2775);
FORCEPROP 1 LAST PART_NUMBER CS04992FB07
J 0
(-7800 2725);
DISPLAY 0.978723 (-7800 2725);
DISPLAY INVISIBLE (-7800 2725);
FORCEPROP 1 LAST TOLERANCE 1%
J 0
(-7750 2525);
DISPLAY 0.978723 (-7750 2525);
DISPLAY INVISIBLE (-7750 2525);
FORCEPROP 1 LAST WATTAGE 1/16W
J 2
(-7775 2475);
DISPLAY 0.978723 (-7775 2475);
DISPLAY INVISIBLE (-7775 2475);
FORCEPROP 1 LAST PACK_TYPE 0402LF
J 0
(-7500 2475);
DISPLAY 0.978723 (-7500 2475);
DISPLAY INVISIBLE (-7500 2475);
FORCEPROP 1 LAST MATERIAL CHIP
J 0
(-7750 2475);
DISPLAY 0.978723 (-7750 2475);
DISPLAY INVISIBLE (-7750 2475);
FORCEADD TAP..1
R 2
(-7700 3225);
FORCEPROP 3 LASTPIN (-7650 3225) SIG_NAME M_K_CPU1_SB_CB<2>
J 0
(-7640 3235);
DISPLAY 0.659574 (-7640 3235);
PAINT MONO (-7640 3235);
DISPLAY INVISIBLE (-7640 3235);
FORCEPROP 1 LASTPIN (-7650 3225) BN 2
J 2
(-7638 3233);
DISPLAY 0.489362 (-7638 3233);
PAINT GREEN (-7638 3233);
FORCEPROP 2 LAST CDS_LIB mstr_standard
J 0
(-7700 3225);
DISPLAY 0.723404 (-7700 3225);
PAINT MONO (-7700 3225);
DISPLAY INVISIBLE (-7700 3225);
FORCEPROP 1 LAST BODY_TYPE PLUMBING
J 2
(-7700 3275);
DISPLAY 0.872340 (-7700 3275);
PAINT GREEN (-7700 3275);
DISPLAY INVISIBLE (-7700 3275);
FORCEPROP 1 LAST HDL_TAP TRUE
J 2
(-8025 3100);
DISPLAY 0.872340 (-8025 3100);
DISPLAY INVISIBLE (-8025 3100);
FORCEPROP 1 LAST PATH I25
J 2
(-7698 3225);
DISPLAY 0.872340 (-7698 3225);
PAINT GREEN (-7698 3225);
DISPLAY INVISIBLE (-7698 3225);
FORCEADD TAP..1
R 2
(-7700 3325);
FORCEPROP 3 LASTPIN (-7650 3325) SIG_NAME M_K_CPU1_SB_CB<4>
J 0
(-7640 3335);
DISPLAY 0.659574 (-7640 3335);
PAINT MONO (-7640 3335);
DISPLAY INVISIBLE (-7640 3335);
FORCEPROP 1 LASTPIN (-7650 3325) BN 4
J 2
(-7638 3333);
DISPLAY 0.489362 (-7638 3333);
PAINT GREEN (-7638 3333);
FORCEPROP 2 LAST CDS_LIB mstr_standard
J 0
(-7700 3325);
DISPLAY 0.723404 (-7700 3325);
PAINT MONO (-7700 3325);
DISPLAY INVISIBLE (-7700 3325);
FORCEPROP 1 LAST BODY_TYPE PLUMBING
J 2
(-7700 3375);
DISPLAY 0.872340 (-7700 3375);
PAINT GREEN (-7700 3375);
DISPLAY INVISIBLE (-7700 3375);
FORCEPROP 1 LAST HDL_TAP TRUE
J 2
(-8025 3200);
DISPLAY 0.872340 (-8025 3200);
DISPLAY INVISIBLE (-8025 3200);
FORCEPROP 1 LAST PATH I26
J 2
(-7698 3325);
DISPLAY 0.872340 (-7698 3325);
PAINT GREEN (-7698 3325);
DISPLAY INVISIBLE (-7698 3325);
FORCEADD TAP..1
R 2
(-7700 3375);
FORCEPROP 3 LASTPIN (-7650 3375) SIG_NAME M_K_CPU1_SB_CB<5>
J 0
(-7640 3385);
DISPLAY 0.659574 (-7640 3385);
PAINT MONO (-7640 3385);
DISPLAY INVISIBLE (-7640 3385);
FORCEPROP 1 LASTPIN (-7650 3375) BN 5
J 2
(-7638 3383);
DISPLAY 0.489362 (-7638 3383);
PAINT GREEN (-7638 3383);
FORCEPROP 2 LAST CDS_LIB mstr_standard
J 0
(-7700 3375);
DISPLAY 0.723404 (-7700 3375);
PAINT MONO (-7700 3375);
DISPLAY INVISIBLE (-7700 3375);
FORCEPROP 1 LAST BODY_TYPE PLUMBING
J 2
(-7700 3425);
DISPLAY 0.872340 (-7700 3425);
PAINT GREEN (-7700 3425);
DISPLAY INVISIBLE (-7700 3425);
FORCEPROP 1 LAST HDL_TAP TRUE
J 2
(-8025 3250);
DISPLAY 0.872340 (-8025 3250);
DISPLAY INVISIBLE (-8025 3250);
FORCEPROP 1 LAST PATH I27
J 2
(-7698 3375);
DISPLAY 0.872340 (-7698 3375);
PAINT GREEN (-7698 3375);
DISPLAY INVISIBLE (-7698 3375);
FORCEADD TAP..1
R 2
(-7700 3275);
FORCEPROP 3 LASTPIN (-7650 3275) SIG_NAME M_K_CPU1_SB_CB<3>
J 0
(-7640 3285);
DISPLAY 0.659574 (-7640 3285);
PAINT MONO (-7640 3285);
DISPLAY INVISIBLE (-7640 3285);
FORCEPROP 1 LASTPIN (-7650 3275) BN 3
J 2
(-7638 3283);
DISPLAY 0.489362 (-7638 3283);
PAINT GREEN (-7638 3283);
FORCEPROP 2 LAST CDS_LIB mstr_standard
J 0
(-7700 3275);
DISPLAY 0.723404 (-7700 3275);
PAINT MONO (-7700 3275);
DISPLAY INVISIBLE (-7700 3275);
FORCEPROP 1 LAST BODY_TYPE PLUMBING
J 2
(-7700 3325);
DISPLAY 0.872340 (-7700 3325);
PAINT GREEN (-7700 3325);
DISPLAY INVISIBLE (-7700 3325);
FORCEPROP 1 LAST HDL_TAP TRUE
J 2
(-8025 3150);
DISPLAY 0.872340 (-8025 3150);
DISPLAY INVISIBLE (-8025 3150);
FORCEPROP 1 LAST PATH I28
J 2
(-7698 3275);
DISPLAY 0.872340 (-7698 3275);
PAINT GREEN (-7698 3275);
DISPLAY INVISIBLE (-7698 3275);
FORCEADD TAP..1
R 2
(-7700 3575);
FORCEPROP 3 LASTPIN (-7650 3575) SIG_NAME M_K_CPU1_SA_CB<0>
J 0
(-7640 3585);
DISPLAY 0.659574 (-7640 3585);
PAINT MONO (-7640 3585);
DISPLAY INVISIBLE (-7640 3585);
FORCEPROP 1 LASTPIN (-7650 3575) BN 0
J 2
(-7638 3583);
DISPLAY 0.489362 (-7638 3583);
PAINT GREEN (-7638 3583);
FORCEPROP 2 LAST CDS_LIB mstr_standard
J 0
(-7700 3575);
DISPLAY 0.723404 (-7700 3575);
PAINT MONO (-7700 3575);
DISPLAY INVISIBLE (-7700 3575);
FORCEPROP 1 LAST BODY_TYPE PLUMBING
J 2
(-7700 3625);
DISPLAY 0.872340 (-7700 3625);
PAINT GREEN (-7700 3625);
DISPLAY INVISIBLE (-7700 3625);
FORCEPROP 1 LAST HDL_TAP TRUE
J 2
(-8025 3450);
DISPLAY 0.872340 (-8025 3450);
DISPLAY INVISIBLE (-8025 3450);
FORCEPROP 1 LAST PATH I29
J 2
(-7698 3575);
DISPLAY 0.872340 (-7698 3575);
PAINT GREEN (-7698 3575);
DISPLAY INVISIBLE (-7698 3575);
FORCEADD TAP..1
R 2
(-7700 3625);
FORCEPROP 3 LASTPIN (-7650 3625) SIG_NAME M_K_CPU1_SA_CB<1>
J 0
(-7640 3635);
DISPLAY 0.659574 (-7640 3635);
PAINT MONO (-7640 3635);
DISPLAY INVISIBLE (-7640 3635);
FORCEPROP 1 LASTPIN (-7650 3625) BN 1
J 2
(-7638 3633);
DISPLAY 0.489362 (-7638 3633);
PAINT GREEN (-7638 3633);
FORCEPROP 2 LAST CDS_LIB mstr_standard
J 0
(-7700 3625);
DISPLAY 0.723404 (-7700 3625);
PAINT MONO (-7700 3625);
DISPLAY INVISIBLE (-7700 3625);
FORCEPROP 1 LAST BODY_TYPE PLUMBING
J 2
(-7700 3675);
DISPLAY 0.872340 (-7700 3675);
PAINT GREEN (-7700 3675);
DISPLAY INVISIBLE (-7700 3675);
FORCEPROP 1 LAST HDL_TAP TRUE
J 2
(-8025 3500);
DISPLAY 0.872340 (-8025 3500);
DISPLAY INVISIBLE (-8025 3500);
FORCEPROP 1 LAST PATH I30
J 2
(-7698 3625);
DISPLAY 0.872340 (-7698 3625);
PAINT GREEN (-7698 3625);
DISPLAY INVISIBLE (-7698 3625);
FORCEADD TAP..1
R 2
(-7700 3425);
FORCEPROP 3 LASTPIN (-7650 3425) SIG_NAME M_K_CPU1_SB_CB<6>
J 0
(-7640 3435);
DISPLAY 0.659574 (-7640 3435);
PAINT MONO (-7640 3435);
DISPLAY INVISIBLE (-7640 3435);
FORCEPROP 1 LASTPIN (-7650 3425) BN 6
J 2
(-7638 3433);
DISPLAY 0.489362 (-7638 3433);
PAINT GREEN (-7638 3433);
FORCEPROP 2 LAST CDS_LIB mstr_standard
J 0
(-7700 3425);
DISPLAY 0.723404 (-7700 3425);
PAINT MONO (-7700 3425);
DISPLAY INVISIBLE (-7700 3425);
FORCEPROP 1 LAST BODY_TYPE PLUMBING
J 2
(-7700 3475);
DISPLAY 0.872340 (-7700 3475);
PAINT GREEN (-7700 3475);
DISPLAY INVISIBLE (-7700 3475);
FORCEPROP 1 LAST HDL_TAP TRUE
J 2
(-8025 3300);
DISPLAY 0.872340 (-8025 3300);
DISPLAY INVISIBLE (-8025 3300);
FORCEPROP 1 LAST PATH I31
J 2
(-7698 3425);
DISPLAY 0.872340 (-7698 3425);
PAINT GREEN (-7698 3425);
DISPLAY INVISIBLE (-7698 3425);
FORCEADD TAP..1
R 2
(-7700 3475);
FORCEPROP 3 LASTPIN (-7650 3475) SIG_NAME M_K_CPU1_SB_CB<7>
J 0
(-7640 3485);
DISPLAY 0.659574 (-7640 3485);
PAINT MONO (-7640 3485);
DISPLAY INVISIBLE (-7640 3485);
FORCEPROP 1 LASTPIN (-7650 3475) BN 7
J 2
(-7638 3483);
DISPLAY 0.489362 (-7638 3483);
PAINT GREEN (-7638 3483);
FORCEPROP 2 LAST CDS_LIB mstr_standard
J 0
(-7700 3475);
DISPLAY 0.723404 (-7700 3475);
PAINT MONO (-7700 3475);
DISPLAY INVISIBLE (-7700 3475);
FORCEPROP 1 LAST BODY_TYPE PLUMBING
J 2
(-7700 3525);
DISPLAY 0.872340 (-7700 3525);
PAINT GREEN (-7700 3525);
DISPLAY INVISIBLE (-7700 3525);
FORCEPROP 1 LAST HDL_TAP TRUE
J 2
(-8025 3350);
DISPLAY 0.872340 (-8025 3350);
DISPLAY INVISIBLE (-8025 3350);
FORCEPROP 1 LAST PATH I32
J 2
(-7698 3475);
DISPLAY 0.872340 (-7698 3475);
PAINT GREEN (-7698 3475);
DISPLAY INVISIBLE (-7698 3475);
FORCEADD TAP..1
(-6000 2125);
FORCEPROP 3 LASTPIN (-6050 2125) SIG_NAME M_K_CPU1_SB_DQ<0>
J 0
(-6040 2135);
DISPLAY 0.659574 (-6040 2135);
PAINT MONO (-6040 2135);
DISPLAY INVISIBLE (-6040 2135);
FORCEPROP 1 LASTPIN (-6050 2125) BN 0
J 0
(-6062 2133);
DISPLAY 0.489362 (-6062 2133);
PAINT GREEN (-6062 2133);
FORCEPROP 2 LAST CDS_LIB mstr_standard
J 0
(-6000 2125);
DISPLAY 0.723404 (-6000 2125);
PAINT MONO (-6000 2125);
DISPLAY INVISIBLE (-6000 2125);
FORCEPROP 1 LAST BODY_TYPE PLUMBING
J 0
(-6000 2175);
DISPLAY 0.872340 (-6000 2175);
PAINT GREEN (-6000 2175);
DISPLAY INVISIBLE (-6000 2175);
FORCEPROP 1 LAST HDL_TAP TRUE
J 0
(-5675 2000);
DISPLAY 0.872340 (-5675 2000);
DISPLAY INVISIBLE (-5675 2000);
FORCEPROP 1 LAST PATH I33
J 0
(-6002 2125);
DISPLAY 0.872340 (-6002 2125);
PAINT GREEN (-6002 2125);
DISPLAY INVISIBLE (-6002 2125);
FORCEADD TAP..1
(-6000 2175);
FORCEPROP 3 LASTPIN (-6050 2175) SIG_NAME M_K_CPU1_SB_DQ<1>
J 0
(-6040 2185);
DISPLAY 0.659574 (-6040 2185);
PAINT MONO (-6040 2185);
DISPLAY INVISIBLE (-6040 2185);
FORCEPROP 1 LASTPIN (-6050 2175) BN 1
J 0
(-6062 2183);
DISPLAY 0.489362 (-6062 2183);
PAINT GREEN (-6062 2183);
FORCEPROP 2 LAST CDS_LIB mstr_standard
J 0
(-6000 2175);
DISPLAY 0.723404 (-6000 2175);
PAINT MONO (-6000 2175);
DISPLAY INVISIBLE (-6000 2175);
FORCEPROP 1 LAST BODY_TYPE PLUMBING
J 0
(-6000 2225);
DISPLAY 0.872340 (-6000 2225);
PAINT GREEN (-6000 2225);
DISPLAY INVISIBLE (-6000 2225);
FORCEPROP 1 LAST HDL_TAP TRUE
J 0
(-5675 2050);
DISPLAY 0.872340 (-5675 2050);
DISPLAY INVISIBLE (-5675 2050);
FORCEPROP 1 LAST PATH I34
J 0
(-6002 2175);
DISPLAY 0.872340 (-6002 2175);
PAINT GREEN (-6002 2175);
DISPLAY INVISIBLE (-6002 2175);
FORCEADD TAP..1
(-6000 2225);
FORCEPROP 3 LASTPIN (-6050 2225) SIG_NAME M_K_CPU1_SB_DQ<2>
J 0
(-6040 2235);
DISPLAY 0.659574 (-6040 2235);
PAINT MONO (-6040 2235);
DISPLAY INVISIBLE (-6040 2235);
FORCEPROP 1 LASTPIN (-6050 2225) BN 2
J 0
(-6062 2233);
DISPLAY 0.489362 (-6062 2233);
PAINT GREEN (-6062 2233);
FORCEPROP 2 LAST CDS_LIB mstr_standard
J 0
(-6000 2225);
DISPLAY 0.723404 (-6000 2225);
PAINT MONO (-6000 2225);
DISPLAY INVISIBLE (-6000 2225);
FORCEPROP 1 LAST BODY_TYPE PLUMBING
J 0
(-6000 2275);
DISPLAY 0.872340 (-6000 2275);
PAINT GREEN (-6000 2275);
DISPLAY INVISIBLE (-6000 2275);
FORCEPROP 1 LAST HDL_TAP TRUE
J 0
(-5675 2100);
DISPLAY 0.872340 (-5675 2100);
DISPLAY INVISIBLE (-5675 2100);
FORCEPROP 1 LAST PATH I35
J 0
(-6002 2225);
DISPLAY 0.872340 (-6002 2225);
PAINT GREEN (-6002 2225);
DISPLAY INVISIBLE (-6002 2225);
FORCEADD TAP..1
(-6000 2275);
FORCEPROP 3 LASTPIN (-6050 2275) SIG_NAME M_K_CPU1_SB_DQ<3>
J 0
(-6040 2285);
DISPLAY 0.659574 (-6040 2285);
PAINT MONO (-6040 2285);
DISPLAY INVISIBLE (-6040 2285);
FORCEPROP 1 LASTPIN (-6050 2275) BN 3
J 0
(-6062 2283);
DISPLAY 0.489362 (-6062 2283);
PAINT GREEN (-6062 2283);
FORCEPROP 2 LAST CDS_LIB mstr_standard
J 0
(-6000 2275);
DISPLAY 0.723404 (-6000 2275);
PAINT MONO (-6000 2275);
DISPLAY INVISIBLE (-6000 2275);
FORCEPROP 1 LAST BODY_TYPE PLUMBING
J 0
(-6000 2325);
DISPLAY 0.872340 (-6000 2325);
PAINT GREEN (-6000 2325);
DISPLAY INVISIBLE (-6000 2325);
FORCEPROP 1 LAST HDL_TAP TRUE
J 0
(-5675 2150);
DISPLAY 0.872340 (-5675 2150);
DISPLAY INVISIBLE (-5675 2150);
FORCEPROP 1 LAST PATH I36
J 0
(-6002 2275);
DISPLAY 0.872340 (-6002 2275);
PAINT GREEN (-6002 2275);
DISPLAY INVISIBLE (-6002 2275);
FORCEADD TAP..1
(-6000 2325);
FORCEPROP 3 LASTPIN (-6050 2325) SIG_NAME M_K_CPU1_SB_DQ<4>
J 0
(-6040 2335);
DISPLAY 0.659574 (-6040 2335);
PAINT MONO (-6040 2335);
DISPLAY INVISIBLE (-6040 2335);
FORCEPROP 1 LASTPIN (-6050 2325) BN 4
J 0
(-6062 2333);
DISPLAY 0.489362 (-6062 2333);
PAINT GREEN (-6062 2333);
FORCEPROP 2 LAST CDS_LIB mstr_standard
J 0
(-6000 2325);
DISPLAY 0.723404 (-6000 2325);
PAINT MONO (-6000 2325);
DISPLAY INVISIBLE (-6000 2325);
FORCEPROP 1 LAST BODY_TYPE PLUMBING
J 0
(-6000 2375);
DISPLAY 0.872340 (-6000 2375);
PAINT GREEN (-6000 2375);
DISPLAY INVISIBLE (-6000 2375);
FORCEPROP 1 LAST HDL_TAP TRUE
J 0
(-5675 2200);
DISPLAY 0.872340 (-5675 2200);
DISPLAY INVISIBLE (-5675 2200);
FORCEPROP 1 LAST PATH I37
J 0
(-6002 2325);
DISPLAY 0.872340 (-6002 2325);
PAINT GREEN (-6002 2325);
DISPLAY INVISIBLE (-6002 2325);
FORCEADD TAP..1
(-6000 2375);
FORCEPROP 3 LASTPIN (-6050 2375) SIG_NAME M_K_CPU1_SB_DQ<5>
J 0
(-6040 2385);
DISPLAY 0.659574 (-6040 2385);
PAINT MONO (-6040 2385);
DISPLAY INVISIBLE (-6040 2385);
FORCEPROP 1 LASTPIN (-6050 2375) BN 5
J 0
(-6062 2383);
DISPLAY 0.489362 (-6062 2383);
PAINT GREEN (-6062 2383);
FORCEPROP 2 LAST CDS_LIB mstr_standard
J 0
(-6000 2375);
DISPLAY 0.723404 (-6000 2375);
PAINT MONO (-6000 2375);
DISPLAY INVISIBLE (-6000 2375);
FORCEPROP 1 LAST BODY_TYPE PLUMBING
J 0
(-6000 2425);
DISPLAY 0.872340 (-6000 2425);
PAINT GREEN (-6000 2425);
DISPLAY INVISIBLE (-6000 2425);
FORCEPROP 1 LAST HDL_TAP TRUE
J 0
(-5675 2250);
DISPLAY 0.872340 (-5675 2250);
DISPLAY INVISIBLE (-5675 2250);
FORCEPROP 1 LAST PATH I38
J 0
(-6002 2375);
DISPLAY 0.872340 (-6002 2375);
PAINT GREEN (-6002 2375);
DISPLAY INVISIBLE (-6002 2375);
FORCEADD TAP..1
(-6000 2425);
FORCEPROP 3 LASTPIN (-6050 2425) SIG_NAME M_K_CPU1_SB_DQ<6>
J 0
(-6040 2435);
DISPLAY 0.659574 (-6040 2435);
PAINT MONO (-6040 2435);
DISPLAY INVISIBLE (-6040 2435);
FORCEPROP 1 LASTPIN (-6050 2425) BN 6
J 0
(-6062 2433);
DISPLAY 0.489362 (-6062 2433);
PAINT GREEN (-6062 2433);
FORCEPROP 2 LAST CDS_LIB mstr_standard
J 0
(-6000 2425);
DISPLAY 0.723404 (-6000 2425);
PAINT MONO (-6000 2425);
DISPLAY INVISIBLE (-6000 2425);
FORCEPROP 1 LAST BODY_TYPE PLUMBING
J 0
(-6000 2475);
DISPLAY 0.872340 (-6000 2475);
PAINT GREEN (-6000 2475);
DISPLAY INVISIBLE (-6000 2475);
FORCEPROP 1 LAST HDL_TAP TRUE
J 0
(-5675 2300);
DISPLAY 0.872340 (-5675 2300);
DISPLAY INVISIBLE (-5675 2300);
FORCEPROP 1 LAST PATH I39
J 0
(-6002 2425);
DISPLAY 0.872340 (-6002 2425);
PAINT GREEN (-6002 2425);
DISPLAY INVISIBLE (-6002 2425);
FORCEADD TAP..1
(-6000 2475);
FORCEPROP 3 LASTPIN (-6050 2475) SIG_NAME M_K_CPU1_SB_DQ<7>
J 0
(-6040 2485);
DISPLAY 0.659574 (-6040 2485);
PAINT MONO (-6040 2485);
DISPLAY INVISIBLE (-6040 2485);
FORCEPROP 1 LASTPIN (-6050 2475) BN 7
J 0
(-6062 2483);
DISPLAY 0.489362 (-6062 2483);
PAINT GREEN (-6062 2483);
FORCEPROP 2 LAST CDS_LIB mstr_standard
J 0
(-6000 2475);
DISPLAY 0.723404 (-6000 2475);
PAINT MONO (-6000 2475);
DISPLAY INVISIBLE (-6000 2475);
FORCEPROP 1 LAST BODY_TYPE PLUMBING
J 0
(-6000 2525);
DISPLAY 0.872340 (-6000 2525);
PAINT GREEN (-6000 2525);
DISPLAY INVISIBLE (-6000 2525);
FORCEPROP 1 LAST HDL_TAP TRUE
J 0
(-5675 2350);
DISPLAY 0.872340 (-5675 2350);
DISPLAY INVISIBLE (-5675 2350);
FORCEPROP 1 LAST PATH I40
J 0
(-6002 2475);
DISPLAY 0.872340 (-6002 2475);
PAINT GREEN (-6002 2475);
DISPLAY INVISIBLE (-6002 2475);
FORCEADD TAP..1
(-6000 2525);
FORCEPROP 3 LASTPIN (-6050 2525) SIG_NAME M_K_CPU1_SB_DQ<8>
J 0
(-6040 2535);
DISPLAY 0.659574 (-6040 2535);
PAINT MONO (-6040 2535);
DISPLAY INVISIBLE (-6040 2535);
FORCEPROP 1 LASTPIN (-6050 2525) BN 8
J 0
(-6062 2533);
DISPLAY 0.489362 (-6062 2533);
PAINT GREEN (-6062 2533);
FORCEPROP 2 LAST CDS_LIB mstr_standard
J 0
(-6000 2525);
DISPLAY 0.723404 (-6000 2525);
PAINT MONO (-6000 2525);
DISPLAY INVISIBLE (-6000 2525);
FORCEPROP 1 LAST BODY_TYPE PLUMBING
J 0
(-6000 2575);
DISPLAY 0.872340 (-6000 2575);
PAINT GREEN (-6000 2575);
DISPLAY INVISIBLE (-6000 2575);
FORCEPROP 1 LAST HDL_TAP TRUE
J 0
(-5675 2400);
DISPLAY 0.872340 (-5675 2400);
DISPLAY INVISIBLE (-5675 2400);
FORCEPROP 1 LAST PATH I41
J 0
(-6002 2525);
DISPLAY 0.872340 (-6002 2525);
PAINT GREEN (-6002 2525);
DISPLAY INVISIBLE (-6002 2525);
FORCEADD TAP..1
(-6000 2625);
FORCEPROP 3 LASTPIN (-6050 2625) SIG_NAME M_K_CPU1_SB_DQ<10>
J 0
(-6040 2635);
DISPLAY 0.659574 (-6040 2635);
PAINT MONO (-6040 2635);
DISPLAY INVISIBLE (-6040 2635);
FORCEPROP 1 LASTPIN (-6050 2625) BN 10
J 0
(-6062 2633);
DISPLAY 0.489362 (-6062 2633);
PAINT GREEN (-6062 2633);
FORCEPROP 2 LAST CDS_LIB mstr_standard
J 0
(-6000 2625);
DISPLAY 0.723404 (-6000 2625);
PAINT MONO (-6000 2625);
DISPLAY INVISIBLE (-6000 2625);
FORCEPROP 1 LAST BODY_TYPE PLUMBING
J 0
(-6000 2675);
DISPLAY 0.872340 (-6000 2675);
PAINT GREEN (-6000 2675);
DISPLAY INVISIBLE (-6000 2675);
FORCEPROP 1 LAST HDL_TAP TRUE
J 0
(-5675 2500);
DISPLAY 0.872340 (-5675 2500);
DISPLAY INVISIBLE (-5675 2500);
FORCEPROP 1 LAST PATH I42
J 0
(-6002 2625);
DISPLAY 0.872340 (-6002 2625);
PAINT GREEN (-6002 2625);
DISPLAY INVISIBLE (-6002 2625);
FORCEADD TAP..1
(-6000 2575);
FORCEPROP 3 LASTPIN (-6050 2575) SIG_NAME M_K_CPU1_SB_DQ<9>
J 0
(-6040 2585);
DISPLAY 0.659574 (-6040 2585);
PAINT MONO (-6040 2585);
DISPLAY INVISIBLE (-6040 2585);
FORCEPROP 1 LASTPIN (-6050 2575) BN 9
J 0
(-6062 2583);
DISPLAY 0.489362 (-6062 2583);
PAINT GREEN (-6062 2583);
FORCEPROP 2 LAST CDS_LIB mstr_standard
J 0
(-6000 2575);
DISPLAY 0.723404 (-6000 2575);
PAINT MONO (-6000 2575);
DISPLAY INVISIBLE (-6000 2575);
FORCEPROP 1 LAST BODY_TYPE PLUMBING
J 0
(-6000 2625);
DISPLAY 0.872340 (-6000 2625);
PAINT GREEN (-6000 2625);
DISPLAY INVISIBLE (-6000 2625);
FORCEPROP 1 LAST HDL_TAP TRUE
J 0
(-5675 2450);
DISPLAY 0.872340 (-5675 2450);
DISPLAY INVISIBLE (-5675 2450);
FORCEPROP 1 LAST PATH I43
J 0
(-6002 2575);
DISPLAY 0.872340 (-6002 2575);
PAINT GREEN (-6002 2575);
DISPLAY INVISIBLE (-6002 2575);
FORCEADD TAP..1
(-6000 2675);
FORCEPROP 3 LASTPIN (-6050 2675) SIG_NAME M_K_CPU1_SB_DQ<11>
J 0
(-6040 2685);
DISPLAY 0.659574 (-6040 2685);
PAINT MONO (-6040 2685);
DISPLAY INVISIBLE (-6040 2685);
FORCEPROP 1 LASTPIN (-6050 2675) BN 11
J 0
(-6062 2683);
DISPLAY 0.489362 (-6062 2683);
PAINT GREEN (-6062 2683);
FORCEPROP 2 LAST CDS_LIB mstr_standard
J 0
(-6000 2675);
DISPLAY 0.723404 (-6000 2675);
PAINT MONO (-6000 2675);
DISPLAY INVISIBLE (-6000 2675);
FORCEPROP 1 LAST BODY_TYPE PLUMBING
J 0
(-6000 2725);
DISPLAY 0.872340 (-6000 2725);
PAINT GREEN (-6000 2725);
DISPLAY INVISIBLE (-6000 2725);
FORCEPROP 1 LAST HDL_TAP TRUE
J 0
(-5675 2550);
DISPLAY 0.872340 (-5675 2550);
DISPLAY INVISIBLE (-5675 2550);
FORCEPROP 1 LAST PATH I44
J 0
(-6002 2675);
DISPLAY 0.872340 (-6002 2675);
PAINT GREEN (-6002 2675);
DISPLAY INVISIBLE (-6002 2675);
FORCEADD TAP..1
(-6000 2725);
FORCEPROP 3 LASTPIN (-6050 2725) SIG_NAME M_K_CPU1_SB_DQ<12>
J 0
(-6040 2735);
DISPLAY 0.659574 (-6040 2735);
PAINT MONO (-6040 2735);
DISPLAY INVISIBLE (-6040 2735);
FORCEPROP 1 LASTPIN (-6050 2725) BN 12
J 0
(-6062 2733);
DISPLAY 0.489362 (-6062 2733);
PAINT GREEN (-6062 2733);
FORCEPROP 2 LAST CDS_LIB mstr_standard
J 0
(-6000 2725);
DISPLAY 0.723404 (-6000 2725);
PAINT MONO (-6000 2725);
DISPLAY INVISIBLE (-6000 2725);
FORCEPROP 1 LAST BODY_TYPE PLUMBING
J 0
(-6000 2775);
DISPLAY 0.872340 (-6000 2775);
PAINT GREEN (-6000 2775);
DISPLAY INVISIBLE (-6000 2775);
FORCEPROP 1 LAST HDL_TAP TRUE
J 0
(-5675 2600);
DISPLAY 0.872340 (-5675 2600);
DISPLAY INVISIBLE (-5675 2600);
FORCEPROP 1 LAST PATH I45
J 0
(-6002 2725);
DISPLAY 0.872340 (-6002 2725);
PAINT GREEN (-6002 2725);
DISPLAY INVISIBLE (-6002 2725);
FORCEADD TAP..1
(-6000 2775);
FORCEPROP 3 LASTPIN (-6050 2775) SIG_NAME M_K_CPU1_SB_DQ<13>
J 0
(-6040 2785);
DISPLAY 0.659574 (-6040 2785);
PAINT MONO (-6040 2785);
DISPLAY INVISIBLE (-6040 2785);
FORCEPROP 1 LASTPIN (-6050 2775) BN 13
J 0
(-6062 2783);
DISPLAY 0.489362 (-6062 2783);
PAINT GREEN (-6062 2783);
FORCEPROP 2 LAST CDS_LIB mstr_standard
J 0
(-6000 2775);
DISPLAY 0.723404 (-6000 2775);
PAINT MONO (-6000 2775);
DISPLAY INVISIBLE (-6000 2775);
FORCEPROP 1 LAST BODY_TYPE PLUMBING
J 0
(-6000 2825);
DISPLAY 0.872340 (-6000 2825);
PAINT GREEN (-6000 2825);
DISPLAY INVISIBLE (-6000 2825);
FORCEPROP 1 LAST HDL_TAP TRUE
J 0
(-5675 2650);
DISPLAY 0.872340 (-5675 2650);
DISPLAY INVISIBLE (-5675 2650);
FORCEPROP 1 LAST PATH I46
J 0
(-6002 2775);
DISPLAY 0.872340 (-6002 2775);
PAINT GREEN (-6002 2775);
DISPLAY INVISIBLE (-6002 2775);
FORCEADD TAP..1
(-6000 2825);
FORCEPROP 3 LASTPIN (-6050 2825) SIG_NAME M_K_CPU1_SB_DQ<14>
J 0
(-6040 2835);
DISPLAY 0.659574 (-6040 2835);
PAINT MONO (-6040 2835);
DISPLAY INVISIBLE (-6040 2835);
FORCEPROP 1 LASTPIN (-6050 2825) BN 14
J 0
(-6062 2833);
DISPLAY 0.489362 (-6062 2833);
PAINT GREEN (-6062 2833);
FORCEPROP 2 LAST CDS_LIB mstr_standard
J 0
(-6000 2825);
DISPLAY 0.723404 (-6000 2825);
PAINT MONO (-6000 2825);
DISPLAY INVISIBLE (-6000 2825);
FORCEPROP 1 LAST BODY_TYPE PLUMBING
J 0
(-6000 2875);
DISPLAY 0.872340 (-6000 2875);
PAINT GREEN (-6000 2875);
DISPLAY INVISIBLE (-6000 2875);
FORCEPROP 1 LAST HDL_TAP TRUE
J 0
(-5675 2700);
DISPLAY 0.872340 (-5675 2700);
DISPLAY INVISIBLE (-5675 2700);
FORCEPROP 1 LAST PATH I47
J 0
(-6002 2825);
DISPLAY 0.872340 (-6002 2825);
PAINT GREEN (-6002 2825);
DISPLAY INVISIBLE (-6002 2825);
FORCEADD TAP..1
(-6000 2875);
FORCEPROP 3 LASTPIN (-6050 2875) SIG_NAME M_K_CPU1_SB_DQ<15>
J 0
(-6040 2885);
DISPLAY 0.659574 (-6040 2885);
PAINT MONO (-6040 2885);
DISPLAY INVISIBLE (-6040 2885);
FORCEPROP 1 LASTPIN (-6050 2875) BN 15
J 0
(-6062 2883);
DISPLAY 0.489362 (-6062 2883);
PAINT GREEN (-6062 2883);
FORCEPROP 2 LAST CDS_LIB mstr_standard
J 0
(-6000 2875);
DISPLAY 0.723404 (-6000 2875);
PAINT MONO (-6000 2875);
DISPLAY INVISIBLE (-6000 2875);
FORCEPROP 1 LAST BODY_TYPE PLUMBING
J 0
(-6000 2925);
DISPLAY 0.872340 (-6000 2925);
PAINT GREEN (-6000 2925);
DISPLAY INVISIBLE (-6000 2925);
FORCEPROP 1 LAST HDL_TAP TRUE
J 0
(-5675 2750);
DISPLAY 0.872340 (-5675 2750);
DISPLAY INVISIBLE (-5675 2750);
FORCEPROP 1 LAST PATH I48
J 0
(-6002 2875);
DISPLAY 0.872340 (-6002 2875);
PAINT GREEN (-6002 2875);
DISPLAY INVISIBLE (-6002 2875);
FORCEADD TAP..1
(-6000 2925);
FORCEPROP 3 LASTPIN (-6050 2925) SIG_NAME M_K_CPU1_SB_DQ<16>
J 0
(-6040 2935);
DISPLAY 0.659574 (-6040 2935);
PAINT MONO (-6040 2935);
DISPLAY INVISIBLE (-6040 2935);
FORCEPROP 1 LASTPIN (-6050 2925) BN 16
J 0
(-6062 2933);
DISPLAY 0.489362 (-6062 2933);
PAINT GREEN (-6062 2933);
FORCEPROP 2 LAST CDS_LIB mstr_standard
J 0
(-6000 2925);
DISPLAY 0.723404 (-6000 2925);
PAINT MONO (-6000 2925);
DISPLAY INVISIBLE (-6000 2925);
FORCEPROP 1 LAST BODY_TYPE PLUMBING
J 0
(-6000 2975);
DISPLAY 0.872340 (-6000 2975);
PAINT GREEN (-6000 2975);
DISPLAY INVISIBLE (-6000 2975);
FORCEPROP 1 LAST HDL_TAP TRUE
J 0
(-5675 2800);
DISPLAY 0.872340 (-5675 2800);
DISPLAY INVISIBLE (-5675 2800);
FORCEPROP 1 LAST PATH I49
J 0
(-6002 2925);
DISPLAY 0.872340 (-6002 2925);
PAINT GREEN (-6002 2925);
DISPLAY INVISIBLE (-6002 2925);
FORCEADD TAP..1
(-6000 2975);
FORCEPROP 3 LASTPIN (-6050 2975) SIG_NAME M_K_CPU1_SB_DQ<17>
J 0
(-6040 2985);
DISPLAY 0.659574 (-6040 2985);
PAINT MONO (-6040 2985);
DISPLAY INVISIBLE (-6040 2985);
FORCEPROP 1 LASTPIN (-6050 2975) BN 17
J 0
(-6062 2983);
DISPLAY 0.489362 (-6062 2983);
PAINT GREEN (-6062 2983);
FORCEPROP 2 LAST CDS_LIB mstr_standard
J 0
(-6000 2975);
DISPLAY 0.723404 (-6000 2975);
PAINT MONO (-6000 2975);
DISPLAY INVISIBLE (-6000 2975);
FORCEPROP 1 LAST BODY_TYPE PLUMBING
J 0
(-6000 3025);
DISPLAY 0.872340 (-6000 3025);
PAINT GREEN (-6000 3025);
DISPLAY INVISIBLE (-6000 3025);
FORCEPROP 1 LAST HDL_TAP TRUE
J 0
(-5675 2850);
DISPLAY 0.872340 (-5675 2850);
DISPLAY INVISIBLE (-5675 2850);
FORCEPROP 1 LAST PATH I50
J 0
(-6002 2975);
DISPLAY 0.872340 (-6002 2975);
PAINT GREEN (-6002 2975);
DISPLAY INVISIBLE (-6002 2975);
FORCEADD TAP..1
(-6000 3025);
FORCEPROP 3 LASTPIN (-6050 3025) SIG_NAME M_K_CPU1_SB_DQ<18>
J 0
(-6040 3035);
DISPLAY 0.659574 (-6040 3035);
PAINT MONO (-6040 3035);
DISPLAY INVISIBLE (-6040 3035);
FORCEPROP 1 LASTPIN (-6050 3025) BN 18
J 0
(-6062 3033);
DISPLAY 0.489362 (-6062 3033);
PAINT GREEN (-6062 3033);
FORCEPROP 2 LAST CDS_LIB mstr_standard
J 0
(-6000 3025);
DISPLAY 0.723404 (-6000 3025);
PAINT MONO (-6000 3025);
DISPLAY INVISIBLE (-6000 3025);
FORCEPROP 1 LAST BODY_TYPE PLUMBING
J 0
(-6000 3075);
DISPLAY 0.872340 (-6000 3075);
PAINT GREEN (-6000 3075);
DISPLAY INVISIBLE (-6000 3075);
FORCEPROP 1 LAST HDL_TAP TRUE
J 0
(-5675 2900);
DISPLAY 0.872340 (-5675 2900);
DISPLAY INVISIBLE (-5675 2900);
FORCEPROP 1 LAST PATH I51
J 0
(-6002 3025);
DISPLAY 0.872340 (-6002 3025);
PAINT GREEN (-6002 3025);
DISPLAY INVISIBLE (-6002 3025);
FORCEADD TAP..1
(-6000 3075);
FORCEPROP 3 LASTPIN (-6050 3075) SIG_NAME M_K_CPU1_SB_DQ<19>
J 0
(-6040 3085);
DISPLAY 0.659574 (-6040 3085);
PAINT MONO (-6040 3085);
DISPLAY INVISIBLE (-6040 3085);
FORCEPROP 1 LASTPIN (-6050 3075) BN 19
J 0
(-6062 3083);
DISPLAY 0.489362 (-6062 3083);
PAINT GREEN (-6062 3083);
FORCEPROP 2 LAST CDS_LIB mstr_standard
J 0
(-6000 3075);
DISPLAY 0.723404 (-6000 3075);
PAINT MONO (-6000 3075);
DISPLAY INVISIBLE (-6000 3075);
FORCEPROP 1 LAST BODY_TYPE PLUMBING
J 0
(-6000 3125);
DISPLAY 0.872340 (-6000 3125);
PAINT GREEN (-6000 3125);
DISPLAY INVISIBLE (-6000 3125);
FORCEPROP 1 LAST HDL_TAP TRUE
J 0
(-5675 2950);
DISPLAY 0.872340 (-5675 2950);
DISPLAY INVISIBLE (-5675 2950);
FORCEPROP 1 LAST PATH I52
J 0
(-6002 3075);
DISPLAY 0.872340 (-6002 3075);
PAINT GREEN (-6002 3075);
DISPLAY INVISIBLE (-6002 3075);
FORCEADD TAP..1
(-6000 3125);
FORCEPROP 3 LASTPIN (-6050 3125) SIG_NAME M_K_CPU1_SB_DQ<20>
J 0
(-6040 3135);
DISPLAY 0.659574 (-6040 3135);
PAINT MONO (-6040 3135);
DISPLAY INVISIBLE (-6040 3135);
FORCEPROP 1 LASTPIN (-6050 3125) BN 20
J 0
(-6062 3133);
DISPLAY 0.489362 (-6062 3133);
PAINT GREEN (-6062 3133);
FORCEPROP 2 LAST CDS_LIB mstr_standard
J 0
(-6000 3125);
DISPLAY 0.723404 (-6000 3125);
PAINT MONO (-6000 3125);
DISPLAY INVISIBLE (-6000 3125);
FORCEPROP 1 LAST BODY_TYPE PLUMBING
J 0
(-6000 3175);
DISPLAY 0.872340 (-6000 3175);
PAINT GREEN (-6000 3175);
DISPLAY INVISIBLE (-6000 3175);
FORCEPROP 1 LAST HDL_TAP TRUE
J 0
(-5675 3000);
DISPLAY 0.872340 (-5675 3000);
DISPLAY INVISIBLE (-5675 3000);
FORCEPROP 1 LAST PATH I53
J 0
(-6002 3125);
DISPLAY 0.872340 (-6002 3125);
PAINT GREEN (-6002 3125);
DISPLAY INVISIBLE (-6002 3125);
FORCEADD TAP..1
(-6000 3175);
FORCEPROP 3 LASTPIN (-6050 3175) SIG_NAME M_K_CPU1_SB_DQ<21>
J 0
(-6040 3185);
DISPLAY 0.659574 (-6040 3185);
PAINT MONO (-6040 3185);
DISPLAY INVISIBLE (-6040 3185);
FORCEPROP 1 LASTPIN (-6050 3175) BN 21
J 0
(-6062 3183);
DISPLAY 0.489362 (-6062 3183);
PAINT GREEN (-6062 3183);
FORCEPROP 2 LAST CDS_LIB mstr_standard
J 0
(-6000 3175);
DISPLAY 0.723404 (-6000 3175);
PAINT MONO (-6000 3175);
DISPLAY INVISIBLE (-6000 3175);
FORCEPROP 1 LAST BODY_TYPE PLUMBING
J 0
(-6000 3225);
DISPLAY 0.872340 (-6000 3225);
PAINT GREEN (-6000 3225);
DISPLAY INVISIBLE (-6000 3225);
FORCEPROP 1 LAST HDL_TAP TRUE
J 0
(-5675 3050);
DISPLAY 0.872340 (-5675 3050);
DISPLAY INVISIBLE (-5675 3050);
FORCEPROP 1 LAST PATH I54
J 0
(-6002 3175);
DISPLAY 0.872340 (-6002 3175);
PAINT GREEN (-6002 3175);
DISPLAY INVISIBLE (-6002 3175);
FORCEADD TAP..1
(-6000 3225);
FORCEPROP 3 LASTPIN (-6050 3225) SIG_NAME M_K_CPU1_SB_DQ<22>
J 0
(-6040 3235);
DISPLAY 0.659574 (-6040 3235);
PAINT MONO (-6040 3235);
DISPLAY INVISIBLE (-6040 3235);
FORCEPROP 1 LASTPIN (-6050 3225) BN 22
J 0
(-6062 3233);
DISPLAY 0.489362 (-6062 3233);
PAINT GREEN (-6062 3233);
FORCEPROP 2 LAST CDS_LIB mstr_standard
J 0
(-6000 3225);
DISPLAY 0.723404 (-6000 3225);
PAINT MONO (-6000 3225);
DISPLAY INVISIBLE (-6000 3225);
FORCEPROP 1 LAST BODY_TYPE PLUMBING
J 0
(-6000 3275);
DISPLAY 0.872340 (-6000 3275);
PAINT GREEN (-6000 3275);
DISPLAY INVISIBLE (-6000 3275);
FORCEPROP 1 LAST HDL_TAP TRUE
J 0
(-5675 3100);
DISPLAY 0.872340 (-5675 3100);
DISPLAY INVISIBLE (-5675 3100);
FORCEPROP 1 LAST PATH I55
J 0
(-6002 3225);
DISPLAY 0.872340 (-6002 3225);
PAINT GREEN (-6002 3225);
DISPLAY INVISIBLE (-6002 3225);
FORCEADD TAP..1
(-6000 3275);
FORCEPROP 3 LASTPIN (-6050 3275) SIG_NAME M_K_CPU1_SB_DQ<23>
J 0
(-6040 3285);
DISPLAY 0.659574 (-6040 3285);
PAINT MONO (-6040 3285);
DISPLAY INVISIBLE (-6040 3285);
FORCEPROP 1 LASTPIN (-6050 3275) BN 23
J 0
(-6062 3283);
DISPLAY 0.489362 (-6062 3283);
PAINT GREEN (-6062 3283);
FORCEPROP 2 LAST CDS_LIB mstr_standard
J 0
(-6000 3275);
DISPLAY 0.723404 (-6000 3275);
PAINT MONO (-6000 3275);
DISPLAY INVISIBLE (-6000 3275);
FORCEPROP 1 LAST BODY_TYPE PLUMBING
J 0
(-6000 3325);
DISPLAY 0.872340 (-6000 3325);
PAINT GREEN (-6000 3325);
DISPLAY INVISIBLE (-6000 3325);
FORCEPROP 1 LAST HDL_TAP TRUE
J 0
(-5675 3150);
DISPLAY 0.872340 (-5675 3150);
DISPLAY INVISIBLE (-5675 3150);
FORCEPROP 1 LAST PATH I56
J 0
(-6002 3275);
DISPLAY 0.872340 (-6002 3275);
PAINT GREEN (-6002 3275);
DISPLAY INVISIBLE (-6002 3275);
FORCEADD TAP..1
(-6000 3325);
FORCEPROP 3 LASTPIN (-6050 3325) SIG_NAME M_K_CPU1_SB_DQ<24>
J 0
(-6040 3335);
DISPLAY 0.659574 (-6040 3335);
PAINT MONO (-6040 3335);
DISPLAY INVISIBLE (-6040 3335);
FORCEPROP 1 LASTPIN (-6050 3325) BN 24
J 0
(-6062 3333);
DISPLAY 0.489362 (-6062 3333);
PAINT GREEN (-6062 3333);
FORCEPROP 2 LAST CDS_LIB mstr_standard
J 0
(-6000 3325);
DISPLAY 0.723404 (-6000 3325);
PAINT MONO (-6000 3325);
DISPLAY INVISIBLE (-6000 3325);
FORCEPROP 1 LAST BODY_TYPE PLUMBING
J 0
(-6000 3375);
DISPLAY 0.872340 (-6000 3375);
PAINT GREEN (-6000 3375);
DISPLAY INVISIBLE (-6000 3375);
FORCEPROP 1 LAST HDL_TAP TRUE
J 0
(-5675 3200);
DISPLAY 0.872340 (-5675 3200);
DISPLAY INVISIBLE (-5675 3200);
FORCEPROP 1 LAST PATH I57
J 0
(-6002 3325);
DISPLAY 0.872340 (-6002 3325);
PAINT GREEN (-6002 3325);
DISPLAY INVISIBLE (-6002 3325);
FORCEADD TAP..1
(-6000 3375);
FORCEPROP 3 LASTPIN (-6050 3375) SIG_NAME M_K_CPU1_SB_DQ<25>
J 0
(-6040 3385);
DISPLAY 0.659574 (-6040 3385);
PAINT MONO (-6040 3385);
DISPLAY INVISIBLE (-6040 3385);
FORCEPROP 1 LASTPIN (-6050 3375) BN 25
J 0
(-6062 3383);
DISPLAY 0.489362 (-6062 3383);
PAINT GREEN (-6062 3383);
FORCEPROP 2 LAST CDS_LIB mstr_standard
J 0
(-6000 3375);
DISPLAY 0.723404 (-6000 3375);
PAINT MONO (-6000 3375);
DISPLAY INVISIBLE (-6000 3375);
FORCEPROP 1 LAST BODY_TYPE PLUMBING
J 0
(-6000 3425);
DISPLAY 0.872340 (-6000 3425);
PAINT GREEN (-6000 3425);
DISPLAY INVISIBLE (-6000 3425);
FORCEPROP 1 LAST HDL_TAP TRUE
J 0
(-5675 3250);
DISPLAY 0.872340 (-5675 3250);
DISPLAY INVISIBLE (-5675 3250);
FORCEPROP 1 LAST PATH I58
J 0
(-6002 3375);
DISPLAY 0.872340 (-6002 3375);
PAINT GREEN (-6002 3375);
DISPLAY INVISIBLE (-6002 3375);
FORCEADD TAP..1
(-6000 3425);
FORCEPROP 3 LASTPIN (-6050 3425) SIG_NAME M_K_CPU1_SB_DQ<26>
J 0
(-6040 3435);
DISPLAY 0.659574 (-6040 3435);
PAINT MONO (-6040 3435);
DISPLAY INVISIBLE (-6040 3435);
FORCEPROP 1 LASTPIN (-6050 3425) BN 26
J 0
(-6062 3433);
DISPLAY 0.489362 (-6062 3433);
PAINT GREEN (-6062 3433);
FORCEPROP 2 LAST CDS_LIB mstr_standard
J 0
(-6000 3425);
DISPLAY 0.723404 (-6000 3425);
PAINT MONO (-6000 3425);
DISPLAY INVISIBLE (-6000 3425);
FORCEPROP 1 LAST BODY_TYPE PLUMBING
J 0
(-6000 3475);
DISPLAY 0.872340 (-6000 3475);
PAINT GREEN (-6000 3475);
DISPLAY INVISIBLE (-6000 3475);
FORCEPROP 1 LAST HDL_TAP TRUE
J 0
(-5675 3300);
DISPLAY 0.872340 (-5675 3300);
DISPLAY INVISIBLE (-5675 3300);
FORCEPROP 1 LAST PATH I59
J 0
(-6002 3425);
DISPLAY 0.872340 (-6002 3425);
PAINT GREEN (-6002 3425);
DISPLAY INVISIBLE (-6002 3425);
FORCEADD OFFPAGE..1
(-8300 2825);
FORCEPROP 2 LAST $XR0 107 
J 0
(-8552 2825);
DISPLAY 0.638298 (-8552 2825);
PAINT MONO (-8552 2825);
FORCEPROP 2 LAST CDS_LIB mstr_standard
J 0
(-8300 2825);
DISPLAY 0.808511 (-8300 2825);
DISPLAY INVISIBLE (-8300 2825);
FORCEPROP 1 LAST OFFPAGE TRUE
J 0
(-7975 2700);
DISPLAY 0.872340 (-7975 2700);
PAINT GREEN (-7975 2700);
DISPLAY INVISIBLE (-7975 2700);
FORCEPROP 1 LAST COMMENT_BODY TRUE
J 0
(-8175 2725);
DISPLAY 0.872340 (-8175 2725);
PAINT GREEN (-8175 2725);
DISPLAY INVISIBLE (-8175 2725);
FORCEPROP 2 LAST PATH I6
J 0
(-8550 2875);
DISPLAY 1.021277 (-8550 2875);
DISPLAY INVISIBLE (-8550 2875);
FORCEADD TAP..1
(-6000 3475);
FORCEPROP 3 LASTPIN (-6050 3475) SIG_NAME M_K_CPU1_SB_DQ<27>
J 0
(-6040 3485);
DISPLAY 0.659574 (-6040 3485);
PAINT MONO (-6040 3485);
DISPLAY INVISIBLE (-6040 3485);
FORCEPROP 1 LASTPIN (-6050 3475) BN 27
J 0
(-6062 3483);
DISPLAY 0.489362 (-6062 3483);
PAINT GREEN (-6062 3483);
FORCEPROP 2 LAST CDS_LIB mstr_standard
J 0
(-6000 3475);
DISPLAY 0.723404 (-6000 3475);
PAINT MONO (-6000 3475);
DISPLAY INVISIBLE (-6000 3475);
FORCEPROP 1 LAST BODY_TYPE PLUMBING
J 0
(-6000 3525);
DISPLAY 0.872340 (-6000 3525);
PAINT GREEN (-6000 3525);
DISPLAY INVISIBLE (-6000 3525);
FORCEPROP 1 LAST HDL_TAP TRUE
J 0
(-5675 3350);
DISPLAY 0.872340 (-5675 3350);
DISPLAY INVISIBLE (-5675 3350);
FORCEPROP 1 LAST PATH I60
J 0
(-6002 3475);
DISPLAY 0.872340 (-6002 3475);
PAINT GREEN (-6002 3475);
DISPLAY INVISIBLE (-6002 3475);
FORCEADD TAP..1
(-6000 3525);
FORCEPROP 3 LASTPIN (-6050 3525) SIG_NAME M_K_CPU1_SB_DQ<28>
J 0
(-6040 3535);
DISPLAY 0.659574 (-6040 3535);
PAINT MONO (-6040 3535);
DISPLAY INVISIBLE (-6040 3535);
FORCEPROP 1 LASTPIN (-6050 3525) BN 28
J 0
(-6062 3533);
DISPLAY 0.489362 (-6062 3533);
PAINT GREEN (-6062 3533);
FORCEPROP 2 LAST CDS_LIB mstr_standard
J 0
(-6000 3525);
DISPLAY 0.723404 (-6000 3525);
PAINT MONO (-6000 3525);
DISPLAY INVISIBLE (-6000 3525);
FORCEPROP 1 LAST BODY_TYPE PLUMBING
J 0
(-6000 3575);
DISPLAY 0.872340 (-6000 3575);
PAINT GREEN (-6000 3575);
DISPLAY INVISIBLE (-6000 3575);
FORCEPROP 1 LAST HDL_TAP TRUE
J 0
(-5675 3400);
DISPLAY 0.872340 (-5675 3400);
DISPLAY INVISIBLE (-5675 3400);
FORCEPROP 1 LAST PATH I61
J 0
(-6002 3525);
DISPLAY 0.872340 (-6002 3525);
PAINT GREEN (-6002 3525);
DISPLAY INVISIBLE (-6002 3525);
FORCEADD TAP..1
(-6000 3575);
FORCEPROP 3 LASTPIN (-6050 3575) SIG_NAME M_K_CPU1_SB_DQ<29>
J 0
(-6040 3585);
DISPLAY 0.659574 (-6040 3585);
PAINT MONO (-6040 3585);
DISPLAY INVISIBLE (-6040 3585);
FORCEPROP 1 LASTPIN (-6050 3575) BN 29
J 0
(-6062 3583);
DISPLAY 0.489362 (-6062 3583);
PAINT GREEN (-6062 3583);
FORCEPROP 2 LAST CDS_LIB mstr_standard
J 0
(-6000 3575);
DISPLAY 0.723404 (-6000 3575);
PAINT MONO (-6000 3575);
DISPLAY INVISIBLE (-6000 3575);
FORCEPROP 1 LAST BODY_TYPE PLUMBING
J 0
(-6000 3625);
DISPLAY 0.872340 (-6000 3625);
PAINT GREEN (-6000 3625);
DISPLAY INVISIBLE (-6000 3625);
FORCEPROP 1 LAST HDL_TAP TRUE
J 0
(-5675 3450);
DISPLAY 0.872340 (-5675 3450);
DISPLAY INVISIBLE (-5675 3450);
FORCEPROP 1 LAST PATH I62
J 0
(-6002 3575);
DISPLAY 0.872340 (-6002 3575);
PAINT GREEN (-6002 3575);
DISPLAY INVISIBLE (-6002 3575);
FORCEADD TAP..1
(-6000 3625);
FORCEPROP 3 LASTPIN (-6050 3625) SIG_NAME M_K_CPU1_SB_DQ<30>
J 0
(-6040 3635);
DISPLAY 0.659574 (-6040 3635);
PAINT MONO (-6040 3635);
DISPLAY INVISIBLE (-6040 3635);
FORCEPROP 1 LASTPIN (-6050 3625) BN 30
J 0
(-6062 3633);
DISPLAY 0.489362 (-6062 3633);
PAINT GREEN (-6062 3633);
FORCEPROP 2 LAST CDS_LIB mstr_standard
J 0
(-6000 3625);
DISPLAY 0.723404 (-6000 3625);
PAINT MONO (-6000 3625);
DISPLAY INVISIBLE (-6000 3625);
FORCEPROP 1 LAST BODY_TYPE PLUMBING
J 0
(-6000 3675);
DISPLAY 0.872340 (-6000 3675);
PAINT GREEN (-6000 3675);
DISPLAY INVISIBLE (-6000 3675);
FORCEPROP 1 LAST HDL_TAP TRUE
J 0
(-5675 3500);
DISPLAY 0.872340 (-5675 3500);
DISPLAY INVISIBLE (-5675 3500);
FORCEPROP 1 LAST PATH I63
J 0
(-6002 3625);
DISPLAY 0.872340 (-6002 3625);
PAINT GREEN (-6002 3625);
DISPLAY INVISIBLE (-6002 3625);
FORCEADD VCC_CORE..1
(-8575 3350);
FORCEPROP 3 LASTPIN (-8575 3300) SIG_NAME P3V3_STBY\g
J 0
(-8565 3310);
DISPLAY 0.659574 (-8565 3310);
PAINT MONO (-8565 3310);
DISPLAY INVISIBLE (-8565 3310);
FORCEPROP 1 LAST HDL_POWER P3V3_STBY
J 1
(-8575 3400);
DISPLAY 0.489362 (-8575 3400);
PAINT GREEN (-8575 3400);
FORCEPROP 2 LAST CDS_LIB mstr_symbols
J 0
(-8575 3350);
PAINT MONO (-8575 3350);
DISPLAY INVISIBLE (-8575 3350);
FORCEPROP 1 LAST PATH I7
J 0
(-8525 3375);
DISPLAY 0.872340 (-8525 3375);
PAINT AQUA (-8525 3375);
DISPLAY INVISIBLE (-8525 3375);
FORCEPROP 0 LAST VOLTAGE 3.3
J 0
(-8850 3500);
DISPLAY 1.021277 (-8850 3500);
PAINT SKYBLUE (-8850 3500);
DISPLAY INVISIBLE (-8850 3500);
FORCEPROP 2 LAST ROOM PVCCINFAON_CPU1_CTRL
J 0
(-8575 3450);
DISPLAY 0.808511 (-8575 3450);
PAINT RED (-8575 3450);
DISPLAY INVISIBLE (-8575 3450);
FORCEADD TAP..1
R 2
(-7700 3675);
FORCEPROP 3 LASTPIN (-7650 3675) SIG_NAME M_K_CPU1_SA_CB<2>
J 0
(-7640 3685);
DISPLAY 0.659574 (-7640 3685);
PAINT MONO (-7640 3685);
DISPLAY INVISIBLE (-7640 3685);
FORCEPROP 1 LASTPIN (-7650 3675) BN 2
J 2
(-7638 3683);
DISPLAY 0.489362 (-7638 3683);
PAINT GREEN (-7638 3683);
FORCEPROP 2 LAST CDS_LIB mstr_standard
J 0
(-7700 3675);
DISPLAY 0.723404 (-7700 3675);
PAINT MONO (-7700 3675);
DISPLAY INVISIBLE (-7700 3675);
FORCEPROP 1 LAST BODY_TYPE PLUMBING
J 2
(-7700 3725);
DISPLAY 0.872340 (-7700 3725);
PAINT GREEN (-7700 3725);
DISPLAY INVISIBLE (-7700 3725);
FORCEPROP 1 LAST HDL_TAP TRUE
J 2
(-8025 3550);
DISPLAY 0.872340 (-8025 3550);
DISPLAY INVISIBLE (-8025 3550);
FORCEPROP 1 LAST PATH I71
J 2
(-7698 3675);
DISPLAY 0.872340 (-7698 3675);
PAINT GREEN (-7698 3675);
DISPLAY INVISIBLE (-7698 3675);
FORCEADD TAP..1
R 2
(-7700 3725);
FORCEPROP 3 LASTPIN (-7650 3725) SIG_NAME M_K_CPU1_SA_CB<3>
J 0
(-7640 3735);
DISPLAY 0.659574 (-7640 3735);
PAINT MONO (-7640 3735);
DISPLAY INVISIBLE (-7640 3735);
FORCEPROP 1 LASTPIN (-7650 3725) BN 3
J 2
(-7638 3733);
DISPLAY 0.489362 (-7638 3733);
PAINT GREEN (-7638 3733);
FORCEPROP 2 LAST CDS_LIB mstr_standard
J 0
(-7700 3725);
DISPLAY 0.723404 (-7700 3725);
PAINT MONO (-7700 3725);
DISPLAY INVISIBLE (-7700 3725);
FORCEPROP 1 LAST BODY_TYPE PLUMBING
J 2
(-7700 3775);
DISPLAY 0.872340 (-7700 3775);
PAINT GREEN (-7700 3775);
DISPLAY INVISIBLE (-7700 3775);
FORCEPROP 1 LAST HDL_TAP TRUE
J 2
(-8025 3600);
DISPLAY 0.872340 (-8025 3600);
DISPLAY INVISIBLE (-8025 3600);
FORCEPROP 1 LAST PATH I72
J 2
(-7698 3725);
DISPLAY 0.872340 (-7698 3725);
PAINT GREEN (-7698 3725);
DISPLAY INVISIBLE (-7698 3725);
FORCEADD TAP..1
R 2
(-7700 3825);
FORCEPROP 3 LASTPIN (-7650 3825) SIG_NAME M_K_CPU1_SA_CB<5>
J 0
(-7640 3835);
DISPLAY 0.659574 (-7640 3835);
PAINT MONO (-7640 3835);
DISPLAY INVISIBLE (-7640 3835);
FORCEPROP 1 LASTPIN (-7650 3825) BN 5
J 2
(-7638 3833);
DISPLAY 0.489362 (-7638 3833);
PAINT GREEN (-7638 3833);
FORCEPROP 2 LAST CDS_LIB mstr_standard
J 0
(-7700 3825);
DISPLAY 0.723404 (-7700 3825);
PAINT MONO (-7700 3825);
DISPLAY INVISIBLE (-7700 3825);
FORCEPROP 1 LAST BODY_TYPE PLUMBING
J 2
(-7700 3875);
DISPLAY 0.872340 (-7700 3875);
PAINT GREEN (-7700 3875);
DISPLAY INVISIBLE (-7700 3875);
FORCEPROP 1 LAST HDL_TAP TRUE
J 2
(-8025 3700);
DISPLAY 0.872340 (-8025 3700);
DISPLAY INVISIBLE (-8025 3700);
FORCEPROP 1 LAST PATH I73
J 2
(-7698 3825);
DISPLAY 0.872340 (-7698 3825);
PAINT GREEN (-7698 3825);
DISPLAY INVISIBLE (-7698 3825);
FORCEADD TAP..1
R 2
(-7700 3875);
FORCEPROP 3 LASTPIN (-7650 3875) SIG_NAME M_K_CPU1_SA_CB<6>
J 0
(-7640 3885);
DISPLAY 0.659574 (-7640 3885);
PAINT MONO (-7640 3885);
DISPLAY INVISIBLE (-7640 3885);
FORCEPROP 1 LASTPIN (-7650 3875) BN 6
J 2
(-7638 3883);
DISPLAY 0.489362 (-7638 3883);
PAINT GREEN (-7638 3883);
FORCEPROP 2 LAST CDS_LIB mstr_standard
J 0
(-7700 3875);
DISPLAY 0.723404 (-7700 3875);
PAINT MONO (-7700 3875);
DISPLAY INVISIBLE (-7700 3875);
FORCEPROP 1 LAST BODY_TYPE PLUMBING
J 2
(-7700 3925);
DISPLAY 0.872340 (-7700 3925);
PAINT GREEN (-7700 3925);
DISPLAY INVISIBLE (-7700 3925);
FORCEPROP 1 LAST HDL_TAP TRUE
J 2
(-8025 3750);
DISPLAY 0.872340 (-8025 3750);
DISPLAY INVISIBLE (-8025 3750);
FORCEPROP 1 LAST PATH I74
J 2
(-7698 3875);
DISPLAY 0.872340 (-7698 3875);
PAINT GREEN (-7698 3875);
DISPLAY INVISIBLE (-7698 3875);
FORCEADD TAP..1
R 2
(-7700 3775);
FORCEPROP 3 LASTPIN (-7650 3775) SIG_NAME M_K_CPU1_SA_CB<4>
J 0
(-7640 3785);
DISPLAY 0.659574 (-7640 3785);
PAINT MONO (-7640 3785);
DISPLAY INVISIBLE (-7640 3785);
FORCEPROP 1 LASTPIN (-7650 3775) BN 4
J 2
(-7638 3783);
DISPLAY 0.489362 (-7638 3783);
PAINT GREEN (-7638 3783);
FORCEPROP 2 LAST CDS_LIB mstr_standard
J 0
(-7700 3775);
DISPLAY 0.723404 (-7700 3775);
PAINT MONO (-7700 3775);
DISPLAY INVISIBLE (-7700 3775);
FORCEPROP 1 LAST BODY_TYPE PLUMBING
J 2
(-7700 3825);
DISPLAY 0.872340 (-7700 3825);
PAINT GREEN (-7700 3825);
DISPLAY INVISIBLE (-7700 3825);
FORCEPROP 1 LAST HDL_TAP TRUE
J 2
(-8025 3650);
DISPLAY 0.872340 (-8025 3650);
DISPLAY INVISIBLE (-8025 3650);
FORCEPROP 1 LAST PATH I75
J 2
(-7698 3775);
DISPLAY 0.872340 (-7698 3775);
PAINT GREEN (-7698 3775);
DISPLAY INVISIBLE (-7698 3775);
FORCEADD TAP..1
R 2
(-7700 3925);
FORCEPROP 3 LASTPIN (-7650 3925) SIG_NAME M_K_CPU1_SA_CB<7>
J 0
(-7640 3935);
DISPLAY 0.659574 (-7640 3935);
PAINT MONO (-7640 3935);
DISPLAY INVISIBLE (-7640 3935);
FORCEPROP 1 LASTPIN (-7650 3925) BN 7
J 2
(-7638 3933);
DISPLAY 0.489362 (-7638 3933);
PAINT GREEN (-7638 3933);
FORCEPROP 2 LAST CDS_LIB mstr_standard
J 0
(-7700 3925);
DISPLAY 0.723404 (-7700 3925);
PAINT MONO (-7700 3925);
DISPLAY INVISIBLE (-7700 3925);
FORCEPROP 1 LAST BODY_TYPE PLUMBING
J 2
(-7700 3975);
DISPLAY 0.872340 (-7700 3975);
PAINT GREEN (-7700 3975);
DISPLAY INVISIBLE (-7700 3975);
FORCEPROP 1 LAST HDL_TAP TRUE
J 2
(-8025 3800);
DISPLAY 0.872340 (-8025 3800);
DISPLAY INVISIBLE (-8025 3800);
FORCEPROP 1 LAST PATH I76
J 2
(-7698 3925);
DISPLAY 0.872340 (-7698 3925);
PAINT GREEN (-7698 3925);
DISPLAY INVISIBLE (-7698 3925);
FORCEADD TAP..1
R 2
(-7700 4625);
FORCEPROP 3 LASTPIN (-7650 4625) SIG_NAME M_K_CPU1_SB_CA<0>
J 0
(-7640 4635);
DISPLAY 0.659574 (-7640 4635);
PAINT MONO (-7640 4635);
DISPLAY INVISIBLE (-7640 4635);
FORCEPROP 1 LASTPIN (-7650 4625) BN 0
J 2
(-7638 4633);
DISPLAY 0.489362 (-7638 4633);
PAINT GREEN (-7638 4633);
FORCEPROP 2 LAST CDS_LIB mstr_standard
J 0
(-7700 4625);
DISPLAY 0.723404 (-7700 4625);
PAINT MONO (-7700 4625);
DISPLAY INVISIBLE (-7700 4625);
FORCEPROP 1 LAST BODY_TYPE PLUMBING
J 2
(-7700 4675);
DISPLAY 0.872340 (-7700 4675);
PAINT GREEN (-7700 4675);
DISPLAY INVISIBLE (-7700 4675);
FORCEPROP 1 LAST HDL_TAP TRUE
J 2
(-8025 4500);
DISPLAY 0.872340 (-8025 4500);
DISPLAY INVISIBLE (-8025 4500);
FORCEPROP 1 LAST PATH I77
J 2
(-7698 4625);
DISPLAY 0.872340 (-7698 4625);
PAINT GREEN (-7698 4625);
DISPLAY INVISIBLE (-7698 4625);
FORCEADD TAP..1
R 2
(-7700 4675);
FORCEPROP 3 LASTPIN (-7650 4675) SIG_NAME M_K_CPU1_SB_CA<1>
J 0
(-7640 4685);
DISPLAY 0.659574 (-7640 4685);
PAINT MONO (-7640 4685);
DISPLAY INVISIBLE (-7640 4685);
FORCEPROP 1 LASTPIN (-7650 4675) BN 1
J 2
(-7638 4683);
DISPLAY 0.489362 (-7638 4683);
PAINT GREEN (-7638 4683);
FORCEPROP 2 LAST CDS_LIB mstr_standard
J 0
(-7700 4675);
DISPLAY 0.723404 (-7700 4675);
PAINT MONO (-7700 4675);
DISPLAY INVISIBLE (-7700 4675);
FORCEPROP 1 LAST BODY_TYPE PLUMBING
J 2
(-7700 4725);
DISPLAY 0.872340 (-7700 4725);
PAINT GREEN (-7700 4725);
DISPLAY INVISIBLE (-7700 4725);
FORCEPROP 1 LAST HDL_TAP TRUE
J 2
(-8025 4550);
DISPLAY 0.872340 (-8025 4550);
DISPLAY INVISIBLE (-8025 4550);
FORCEPROP 1 LAST PATH I78
J 2
(-7698 4675);
DISPLAY 0.872340 (-7698 4675);
PAINT GREEN (-7698 4675);
DISPLAY INVISIBLE (-7698 4675);
FORCEADD TAP..1
R 2
(-7700 4725);
FORCEPROP 3 LASTPIN (-7650 4725) SIG_NAME M_K_CPU1_SB_CA<2>
J 0
(-7640 4735);
DISPLAY 0.659574 (-7640 4735);
PAINT MONO (-7640 4735);
DISPLAY INVISIBLE (-7640 4735);
FORCEPROP 1 LASTPIN (-7650 4725) BN 2
J 2
(-7638 4733);
DISPLAY 0.489362 (-7638 4733);
PAINT GREEN (-7638 4733);
FORCEPROP 2 LAST CDS_LIB mstr_standard
J 0
(-7700 4725);
DISPLAY 0.723404 (-7700 4725);
PAINT MONO (-7700 4725);
DISPLAY INVISIBLE (-7700 4725);
FORCEPROP 1 LAST BODY_TYPE PLUMBING
J 2
(-7700 4775);
DISPLAY 0.872340 (-7700 4775);
PAINT GREEN (-7700 4775);
DISPLAY INVISIBLE (-7700 4775);
FORCEPROP 1 LAST HDL_TAP TRUE
J 2
(-8025 4600);
DISPLAY 0.872340 (-8025 4600);
DISPLAY INVISIBLE (-8025 4600);
FORCEPROP 1 LAST PATH I79
J 2
(-7698 4725);
DISPLAY 0.872340 (-7698 4725);
PAINT GREEN (-7698 4725);
DISPLAY INVISIBLE (-7698 4725);
FORCEADD OFFPAGE..5
(-8150 2975);
FORCEPROP 2 LAST $XR0 47 
J 0
(-8374 2975);
DISPLAY 0.638298 (-8374 2975);
PAINT MONO (-8374 2975);
FORCEPROP 2 LAST CDS_LIB mstr_standard
J 0
(-8150 2975);
DISPLAY INVISIBLE (-8150 2975);
FORCEPROP 1 LAST OFFPAGE TRUE
J 0
(-7825 2850);
DISPLAY 0.872340 (-7825 2850);
PAINT GREEN (-7825 2850);
DISPLAY INVISIBLE (-7825 2850);
FORCEPROP 1 LAST COMMENT_BODY TRUE
J 0
(-8050 2900);
DISPLAY 0.872340 (-8050 2900);
PAINT GREEN (-8050 2900);
DISPLAY INVISIBLE (-8050 2900);
FORCEPROP 2 LAST PATH I8
J 0
(-8350 3025);
DISPLAY 1.021277 (-8350 3025);
DISPLAY INVISIBLE (-8350 3025);
FORCEADD TAP..1
R 2
(-7700 4775);
FORCEPROP 3 LASTPIN (-7650 4775) SIG_NAME M_K_CPU1_SB_CA<3>
J 0
(-7640 4785);
DISPLAY 0.659574 (-7640 4785);
PAINT MONO (-7640 4785);
DISPLAY INVISIBLE (-7640 4785);
FORCEPROP 1 LASTPIN (-7650 4775) BN 3
J 2
(-7638 4783);
DISPLAY 0.489362 (-7638 4783);
PAINT GREEN (-7638 4783);
FORCEPROP 2 LAST CDS_LIB mstr_standard
J 0
(-7700 4775);
DISPLAY 0.723404 (-7700 4775);
PAINT MONO (-7700 4775);
DISPLAY INVISIBLE (-7700 4775);
FORCEPROP 1 LAST BODY_TYPE PLUMBING
J 2
(-7700 4825);
DISPLAY 0.872340 (-7700 4825);
PAINT GREEN (-7700 4825);
DISPLAY INVISIBLE (-7700 4825);
FORCEPROP 1 LAST HDL_TAP TRUE
J 2
(-8025 4650);
DISPLAY 0.872340 (-8025 4650);
DISPLAY INVISIBLE (-8025 4650);
FORCEPROP 1 LAST PATH I80
J 2
(-7698 4775);
DISPLAY 0.872340 (-7698 4775);
PAINT GREEN (-7698 4775);
DISPLAY INVISIBLE (-7698 4775);
FORCEADD TAP..1
R 2
(-7700 4825);
FORCEPROP 3 LASTPIN (-7650 4825) SIG_NAME M_K_CPU1_SB_CA<4>
J 0
(-7640 4835);
DISPLAY 0.659574 (-7640 4835);
PAINT MONO (-7640 4835);
DISPLAY INVISIBLE (-7640 4835);
FORCEPROP 1 LASTPIN (-7650 4825) BN 4
J 2
(-7638 4833);
DISPLAY 0.489362 (-7638 4833);
PAINT GREEN (-7638 4833);
FORCEPROP 2 LAST CDS_LIB mstr_standard
J 0
(-7700 4825);
DISPLAY 0.723404 (-7700 4825);
PAINT MONO (-7700 4825);
DISPLAY INVISIBLE (-7700 4825);
FORCEPROP 1 LAST BODY_TYPE PLUMBING
J 2
(-7700 4875);
DISPLAY 0.872340 (-7700 4875);
PAINT GREEN (-7700 4875);
DISPLAY INVISIBLE (-7700 4875);
FORCEPROP 1 LAST HDL_TAP TRUE
J 2
(-8025 4700);
DISPLAY 0.872340 (-8025 4700);
DISPLAY INVISIBLE (-8025 4700);
FORCEPROP 1 LAST PATH I81
J 2
(-7698 4825);
DISPLAY 0.872340 (-7698 4825);
PAINT GREEN (-7698 4825);
DISPLAY INVISIBLE (-7698 4825);
FORCEADD TAP..1
R 2
(-7700 4925);
FORCEPROP 3 LASTPIN (-7650 4925) SIG_NAME M_K_CPU1_SB_CA<6>
J 0
(-7640 4935);
DISPLAY 0.659574 (-7640 4935);
PAINT MONO (-7640 4935);
DISPLAY INVISIBLE (-7640 4935);
FORCEPROP 1 LASTPIN (-7650 4925) BN 6
J 2
(-7638 4933);
DISPLAY 0.489362 (-7638 4933);
PAINT GREEN (-7638 4933);
FORCEPROP 2 LAST CDS_LIB mstr_standard
J 0
(-7700 4925);
DISPLAY 0.723404 (-7700 4925);
PAINT MONO (-7700 4925);
DISPLAY INVISIBLE (-7700 4925);
FORCEPROP 1 LAST BODY_TYPE PLUMBING
J 2
(-7700 4975);
DISPLAY 0.872340 (-7700 4975);
PAINT GREEN (-7700 4975);
DISPLAY INVISIBLE (-7700 4975);
FORCEPROP 1 LAST HDL_TAP TRUE
J 2
(-8025 4800);
DISPLAY 0.872340 (-8025 4800);
DISPLAY INVISIBLE (-8025 4800);
FORCEPROP 1 LAST PATH I82
J 2
(-7698 4925);
DISPLAY 0.872340 (-7698 4925);
PAINT GREEN (-7698 4925);
DISPLAY INVISIBLE (-7698 4925);
FORCEADD TAP..1
R 2
(-7700 4875);
FORCEPROP 3 LASTPIN (-7650 4875) SIG_NAME M_K_CPU1_SB_CA<5>
J 0
(-7640 4885);
DISPLAY 0.659574 (-7640 4885);
PAINT MONO (-7640 4885);
DISPLAY INVISIBLE (-7640 4885);
FORCEPROP 1 LASTPIN (-7650 4875) BN 5
J 2
(-7638 4883);
DISPLAY 0.489362 (-7638 4883);
PAINT GREEN (-7638 4883);
FORCEPROP 2 LAST CDS_LIB mstr_standard
J 0
(-7700 4875);
DISPLAY 0.723404 (-7700 4875);
PAINT MONO (-7700 4875);
DISPLAY INVISIBLE (-7700 4875);
FORCEPROP 1 LAST BODY_TYPE PLUMBING
J 2
(-7700 4925);
DISPLAY 0.872340 (-7700 4925);
PAINT GREEN (-7700 4925);
DISPLAY INVISIBLE (-7700 4925);
FORCEPROP 1 LAST HDL_TAP TRUE
J 2
(-8025 4750);
DISPLAY 0.872340 (-8025 4750);
DISPLAY INVISIBLE (-8025 4750);
FORCEPROP 1 LAST PATH I83
J 2
(-7698 4875);
DISPLAY 0.872340 (-7698 4875);
PAINT GREEN (-7698 4875);
DISPLAY INVISIBLE (-7698 4875);
FORCEADD TAP..1
R 2
(-7700 5075);
FORCEPROP 3 LASTPIN (-7650 5075) SIG_NAME M_K_CPU1_SA_CA<1>
J 0
(-7640 5085);
DISPLAY 0.659574 (-7640 5085);
PAINT MONO (-7640 5085);
DISPLAY INVISIBLE (-7640 5085);
FORCEPROP 1 LASTPIN (-7650 5075) BN 1
J 2
(-7638 5083);
DISPLAY 0.489362 (-7638 5083);
PAINT GREEN (-7638 5083);
FORCEPROP 2 LAST CDS_LIB mstr_standard
J 0
(-7700 5075);
DISPLAY 0.723404 (-7700 5075);
PAINT MONO (-7700 5075);
DISPLAY INVISIBLE (-7700 5075);
FORCEPROP 1 LAST BODY_TYPE PLUMBING
J 2
(-7700 5125);
DISPLAY 0.872340 (-7700 5125);
PAINT GREEN (-7700 5125);
DISPLAY INVISIBLE (-7700 5125);
FORCEPROP 1 LAST HDL_TAP TRUE
J 2
(-8025 4950);
DISPLAY 0.872340 (-8025 4950);
DISPLAY INVISIBLE (-8025 4950);
FORCEPROP 1 LAST PATH I84
J 2
(-7698 5075);
DISPLAY 0.872340 (-7698 5075);
PAINT GREEN (-7698 5075);
DISPLAY INVISIBLE (-7698 5075);
FORCEADD TAP..1
R 2
(-7700 5125);
FORCEPROP 3 LASTPIN (-7650 5125) SIG_NAME M_K_CPU1_SA_CA<2>
J 0
(-7640 5135);
DISPLAY 0.659574 (-7640 5135);
PAINT MONO (-7640 5135);
DISPLAY INVISIBLE (-7640 5135);
FORCEPROP 1 LASTPIN (-7650 5125) BN 2
J 2
(-7638 5133);
DISPLAY 0.489362 (-7638 5133);
PAINT GREEN (-7638 5133);
FORCEPROP 2 LAST CDS_LIB mstr_standard
J 0
(-7700 5125);
DISPLAY 0.723404 (-7700 5125);
PAINT MONO (-7700 5125);
DISPLAY INVISIBLE (-7700 5125);
FORCEPROP 1 LAST BODY_TYPE PLUMBING
J 2
(-7700 5175);
DISPLAY 0.872340 (-7700 5175);
PAINT GREEN (-7700 5175);
DISPLAY INVISIBLE (-7700 5175);
FORCEPROP 1 LAST HDL_TAP TRUE
J 2
(-8025 5000);
DISPLAY 0.872340 (-8025 5000);
DISPLAY INVISIBLE (-8025 5000);
FORCEPROP 1 LAST PATH I85
J 2
(-7698 5125);
DISPLAY 0.872340 (-7698 5125);
PAINT GREEN (-7698 5125);
DISPLAY INVISIBLE (-7698 5125);
FORCEADD TAP..1
R 2
(-7700 5175);
FORCEPROP 3 LASTPIN (-7650 5175) SIG_NAME M_K_CPU1_SA_CA<3>
J 0
(-7640 5185);
DISPLAY 0.659574 (-7640 5185);
PAINT MONO (-7640 5185);
DISPLAY INVISIBLE (-7640 5185);
FORCEPROP 1 LASTPIN (-7650 5175) BN 3
J 2
(-7638 5183);
DISPLAY 0.489362 (-7638 5183);
PAINT GREEN (-7638 5183);
FORCEPROP 2 LAST CDS_LIB mstr_standard
J 0
(-7700 5175);
DISPLAY 0.723404 (-7700 5175);
PAINT MONO (-7700 5175);
DISPLAY INVISIBLE (-7700 5175);
FORCEPROP 1 LAST BODY_TYPE PLUMBING
J 2
(-7700 5225);
DISPLAY 0.872340 (-7700 5225);
PAINT GREEN (-7700 5225);
DISPLAY INVISIBLE (-7700 5225);
FORCEPROP 1 LAST HDL_TAP TRUE
J 2
(-8025 5050);
DISPLAY 0.872340 (-8025 5050);
DISPLAY INVISIBLE (-8025 5050);
FORCEPROP 1 LAST PATH I86
J 2
(-7698 5175);
DISPLAY 0.872340 (-7698 5175);
PAINT GREEN (-7698 5175);
DISPLAY INVISIBLE (-7698 5175);
FORCEADD TAP..1
R 2
(-7700 5025);
FORCEPROP 3 LASTPIN (-7650 5025) SIG_NAME M_K_CPU1_SA_CA<0>
J 0
(-7640 5035);
DISPLAY 0.659574 (-7640 5035);
PAINT MONO (-7640 5035);
DISPLAY INVISIBLE (-7640 5035);
FORCEPROP 1 LASTPIN (-7650 5025) BN 0
J 2
(-7638 5033);
DISPLAY 0.489362 (-7638 5033);
PAINT GREEN (-7638 5033);
FORCEPROP 2 LAST CDS_LIB mstr_standard
J 0
(-7700 5025);
DISPLAY 0.723404 (-7700 5025);
PAINT MONO (-7700 5025);
DISPLAY INVISIBLE (-7700 5025);
FORCEPROP 1 LAST BODY_TYPE PLUMBING
J 2
(-7700 5075);
DISPLAY 0.872340 (-7700 5075);
PAINT GREEN (-7700 5075);
DISPLAY INVISIBLE (-7700 5075);
FORCEPROP 1 LAST HDL_TAP TRUE
J 2
(-8025 4900);
DISPLAY 0.872340 (-8025 4900);
DISPLAY INVISIBLE (-8025 4900);
FORCEPROP 1 LAST PATH I87
J 2
(-7698 5025);
DISPLAY 0.872340 (-7698 5025);
PAINT GREEN (-7698 5025);
DISPLAY INVISIBLE (-7698 5025);
FORCEADD TAP..1
R 2
(-7700 5275);
FORCEPROP 3 LASTPIN (-7650 5275) SIG_NAME M_K_CPU1_SA_CA<5>
J 0
(-7640 5285);
DISPLAY 0.659574 (-7640 5285);
PAINT MONO (-7640 5285);
DISPLAY INVISIBLE (-7640 5285);
FORCEPROP 1 LASTPIN (-7650 5275) BN 5
J 2
(-7638 5283);
DISPLAY 0.489362 (-7638 5283);
PAINT GREEN (-7638 5283);
FORCEPROP 2 LAST CDS_LIB mstr_standard
J 0
(-7700 5275);
DISPLAY 0.723404 (-7700 5275);
PAINT MONO (-7700 5275);
DISPLAY INVISIBLE (-7700 5275);
FORCEPROP 1 LAST BODY_TYPE PLUMBING
J 2
(-7700 5325);
DISPLAY 0.872340 (-7700 5325);
PAINT GREEN (-7700 5325);
DISPLAY INVISIBLE (-7700 5325);
FORCEPROP 1 LAST HDL_TAP TRUE
J 2
(-8025 5150);
DISPLAY 0.872340 (-8025 5150);
DISPLAY INVISIBLE (-8025 5150);
FORCEPROP 1 LAST PATH I88
J 2
(-7698 5275);
DISPLAY 0.872340 (-7698 5275);
PAINT GREEN (-7698 5275);
DISPLAY INVISIBLE (-7698 5275);
FORCEADD TAP..1
R 2
(-7700 5325);
FORCEPROP 3 LASTPIN (-7650 5325) SIG_NAME M_K_CPU1_SA_CA<6>
J 0
(-7640 5335);
DISPLAY 0.659574 (-7640 5335);
PAINT MONO (-7640 5335);
DISPLAY INVISIBLE (-7640 5335);
FORCEPROP 1 LASTPIN (-7650 5325) BN 6
J 2
(-7638 5333);
DISPLAY 0.489362 (-7638 5333);
PAINT GREEN (-7638 5333);
FORCEPROP 2 LAST CDS_LIB mstr_standard
J 0
(-7700 5325);
DISPLAY 0.723404 (-7700 5325);
PAINT MONO (-7700 5325);
DISPLAY INVISIBLE (-7700 5325);
FORCEPROP 1 LAST BODY_TYPE PLUMBING
J 2
(-7700 5375);
DISPLAY 0.872340 (-7700 5375);
PAINT GREEN (-7700 5375);
DISPLAY INVISIBLE (-7700 5375);
FORCEPROP 1 LAST HDL_TAP TRUE
J 2
(-8025 5200);
DISPLAY 0.872340 (-8025 5200);
DISPLAY INVISIBLE (-8025 5200);
FORCEPROP 1 LAST PATH I89
J 2
(-7698 5325);
DISPLAY 0.872340 (-7698 5325);
PAINT GREEN (-7698 5325);
DISPLAY INVISIBLE (-7698 5325);
FORCEADD OFFPAGE..1
(-8150 3025);
FORCEPROP 2 LAST $XR0 47 
J 0
(-8401 3025);
DISPLAY 0.638298 (-8401 3025);
PAINT MONO (-8401 3025);
FORCEPROP 2 LAST CDS_LIB mstr_standard
J 0
(-8150 3025);
DISPLAY 0.808511 (-8150 3025);
DISPLAY INVISIBLE (-8150 3025);
FORCEPROP 1 LAST OFFPAGE TRUE
J 0
(-7825 2900);
DISPLAY 0.872340 (-7825 2900);
PAINT GREEN (-7825 2900);
DISPLAY INVISIBLE (-7825 2900);
FORCEPROP 1 LAST COMMENT_BODY TRUE
J 0
(-8025 2925);
DISPLAY 0.872340 (-8025 2925);
PAINT GREEN (-8025 2925);
DISPLAY INVISIBLE (-8025 2925);
FORCEPROP 2 LAST PATH I9
J 0
(-8350 3075);
DISPLAY 1.021277 (-8350 3075);
DISPLAY INVISIBLE (-8350 3075);
FORCEADD TAP..1
R 2
(-7700 5225);
FORCEPROP 3 LASTPIN (-7650 5225) SIG_NAME M_K_CPU1_SA_CA<4>
J 0
(-7640 5235);
DISPLAY 0.659574 (-7640 5235);
PAINT MONO (-7640 5235);
DISPLAY INVISIBLE (-7640 5235);
FORCEPROP 1 LASTPIN (-7650 5225) BN 4
J 2
(-7638 5233);
DISPLAY 0.489362 (-7638 5233);
PAINT GREEN (-7638 5233);
FORCEPROP 2 LAST CDS_LIB mstr_standard
J 0
(-7700 5225);
DISPLAY 0.723404 (-7700 5225);
PAINT MONO (-7700 5225);
DISPLAY INVISIBLE (-7700 5225);
FORCEPROP 1 LAST BODY_TYPE PLUMBING
J 2
(-7700 5275);
DISPLAY 0.872340 (-7700 5275);
PAINT GREEN (-7700 5275);
DISPLAY INVISIBLE (-7700 5275);
FORCEPROP 1 LAST HDL_TAP TRUE
J 2
(-8025 5100);
DISPLAY 0.872340 (-8025 5100);
DISPLAY INVISIBLE (-8025 5100);
FORCEPROP 1 LAST PATH I90
J 2
(-7698 5225);
DISPLAY 0.872340 (-7698 5225);
PAINT GREEN (-7698 5225);
DISPLAY INVISIBLE (-7698 5225);
FORCEADD TAP..1
(-6000 3675);
FORCEPROP 3 LASTPIN (-6050 3675) SIG_NAME M_K_CPU1_SB_DQ<31>
J 0
(-6040 3685);
DISPLAY 0.659574 (-6040 3685);
PAINT MONO (-6040 3685);
DISPLAY INVISIBLE (-6040 3685);
FORCEPROP 1 LASTPIN (-6050 3675) BN 31
J 0
(-6062 3683);
DISPLAY 0.489362 (-6062 3683);
PAINT GREEN (-6062 3683);
FORCEPROP 2 LAST CDS_LIB mstr_standard
J 0
(-6000 3675);
DISPLAY 0.723404 (-6000 3675);
PAINT MONO (-6000 3675);
DISPLAY INVISIBLE (-6000 3675);
FORCEPROP 1 LAST BODY_TYPE PLUMBING
J 0
(-6000 3725);
DISPLAY 0.872340 (-6000 3725);
PAINT GREEN (-6000 3725);
DISPLAY INVISIBLE (-6000 3725);
FORCEPROP 1 LAST HDL_TAP TRUE
J 0
(-5675 3550);
DISPLAY 0.872340 (-5675 3550);
DISPLAY INVISIBLE (-5675 3550);
FORCEPROP 1 LAST PATH I91
J 0
(-6002 3675);
DISPLAY 0.872340 (-6002 3675);
PAINT GREEN (-6002 3675);
DISPLAY INVISIBLE (-6002 3675);
FORCEADD TAP..1
(-6000 3775);
FORCEPROP 3 LASTPIN (-6050 3775) SIG_NAME M_K_CPU1_SA_DQ<0>
J 0
(-6040 3785);
DISPLAY 0.659574 (-6040 3785);
PAINT MONO (-6040 3785);
DISPLAY INVISIBLE (-6040 3785);
FORCEPROP 1 LASTPIN (-6050 3775) BN 0
J 0
(-6062 3783);
DISPLAY 0.489362 (-6062 3783);
PAINT GREEN (-6062 3783);
FORCEPROP 2 LAST CDS_LIB mstr_standard
J 0
(-6000 3775);
DISPLAY 0.723404 (-6000 3775);
PAINT MONO (-6000 3775);
DISPLAY INVISIBLE (-6000 3775);
FORCEPROP 1 LAST BODY_TYPE PLUMBING
J 0
(-6000 3825);
DISPLAY 0.872340 (-6000 3825);
PAINT GREEN (-6000 3825);
DISPLAY INVISIBLE (-6000 3825);
FORCEPROP 1 LAST HDL_TAP TRUE
J 0
(-5675 3650);
DISPLAY 0.872340 (-5675 3650);
DISPLAY INVISIBLE (-5675 3650);
FORCEPROP 1 LAST PATH I92
J 0
(-6002 3775);
DISPLAY 0.872340 (-6002 3775);
PAINT GREEN (-6002 3775);
DISPLAY INVISIBLE (-6002 3775);
FORCEADD TAP..1
(-6000 3825);
FORCEPROP 3 LASTPIN (-6050 3825) SIG_NAME M_K_CPU1_SA_DQ<1>
J 0
(-6040 3835);
DISPLAY 0.659574 (-6040 3835);
PAINT MONO (-6040 3835);
DISPLAY INVISIBLE (-6040 3835);
FORCEPROP 1 LASTPIN (-6050 3825) BN 1
J 0
(-6062 3833);
DISPLAY 0.489362 (-6062 3833);
PAINT GREEN (-6062 3833);
FORCEPROP 2 LAST CDS_LIB mstr_standard
J 0
(-6000 3825);
DISPLAY 0.723404 (-6000 3825);
PAINT MONO (-6000 3825);
DISPLAY INVISIBLE (-6000 3825);
FORCEPROP 1 LAST BODY_TYPE PLUMBING
J 0
(-6000 3875);
DISPLAY 0.872340 (-6000 3875);
PAINT GREEN (-6000 3875);
DISPLAY INVISIBLE (-6000 3875);
FORCEPROP 1 LAST HDL_TAP TRUE
J 0
(-5675 3700);
DISPLAY 0.872340 (-5675 3700);
DISPLAY INVISIBLE (-5675 3700);
FORCEPROP 1 LAST PATH I93
J 0
(-6002 3825);
DISPLAY 0.872340 (-6002 3825);
PAINT GREEN (-6002 3825);
DISPLAY INVISIBLE (-6002 3825);
FORCEADD TAP..1
(-6000 3875);
FORCEPROP 3 LASTPIN (-6050 3875) SIG_NAME M_K_CPU1_SA_DQ<2>
J 0
(-6040 3885);
DISPLAY 0.659574 (-6040 3885);
PAINT MONO (-6040 3885);
DISPLAY INVISIBLE (-6040 3885);
FORCEPROP 1 LASTPIN (-6050 3875) BN 2
J 0
(-6062 3883);
DISPLAY 0.489362 (-6062 3883);
PAINT GREEN (-6062 3883);
FORCEPROP 2 LAST CDS_LIB mstr_standard
J 0
(-6000 3875);
DISPLAY 0.723404 (-6000 3875);
PAINT MONO (-6000 3875);
DISPLAY INVISIBLE (-6000 3875);
FORCEPROP 1 LAST BODY_TYPE PLUMBING
J 0
(-6000 3925);
DISPLAY 0.872340 (-6000 3925);
PAINT GREEN (-6000 3925);
DISPLAY INVISIBLE (-6000 3925);
FORCEPROP 1 LAST HDL_TAP TRUE
J 0
(-5675 3750);
DISPLAY 0.872340 (-5675 3750);
DISPLAY INVISIBLE (-5675 3750);
FORCEPROP 1 LAST PATH I94
J 0
(-6002 3875);
DISPLAY 0.872340 (-6002 3875);
PAINT GREEN (-6002 3875);
DISPLAY INVISIBLE (-6002 3875);
FORCEADD TAP..1
(-6000 3925);
FORCEPROP 3 LASTPIN (-6050 3925) SIG_NAME M_K_CPU1_SA_DQ<3>
J 0
(-6040 3935);
DISPLAY 0.659574 (-6040 3935);
PAINT MONO (-6040 3935);
DISPLAY INVISIBLE (-6040 3935);
FORCEPROP 1 LASTPIN (-6050 3925) BN 3
J 0
(-6062 3933);
DISPLAY 0.489362 (-6062 3933);
PAINT GREEN (-6062 3933);
FORCEPROP 2 LAST CDS_LIB mstr_standard
J 0
(-6000 3925);
DISPLAY 0.723404 (-6000 3925);
PAINT MONO (-6000 3925);
DISPLAY INVISIBLE (-6000 3925);
FORCEPROP 1 LAST BODY_TYPE PLUMBING
J 0
(-6000 3975);
DISPLAY 0.872340 (-6000 3975);
PAINT GREEN (-6000 3975);
DISPLAY INVISIBLE (-6000 3975);
FORCEPROP 1 LAST HDL_TAP TRUE
J 0
(-5675 3800);
DISPLAY 0.872340 (-5675 3800);
DISPLAY INVISIBLE (-5675 3800);
FORCEPROP 1 LAST PATH I95
J 0
(-6002 3925);
DISPLAY 0.872340 (-6002 3925);
PAINT GREEN (-6002 3925);
DISPLAY INVISIBLE (-6002 3925);
FORCEADD TAP..1
(-6000 3975);
FORCEPROP 3 LASTPIN (-6050 3975) SIG_NAME M_K_CPU1_SA_DQ<4>
J 0
(-6040 3985);
DISPLAY 0.659574 (-6040 3985);
PAINT MONO (-6040 3985);
DISPLAY INVISIBLE (-6040 3985);
FORCEPROP 1 LASTPIN (-6050 3975) BN 4
J 0
(-6062 3983);
DISPLAY 0.489362 (-6062 3983);
PAINT GREEN (-6062 3983);
FORCEPROP 2 LAST CDS_LIB mstr_standard
J 0
(-6000 3975);
DISPLAY 0.723404 (-6000 3975);
PAINT MONO (-6000 3975);
DISPLAY INVISIBLE (-6000 3975);
FORCEPROP 1 LAST BODY_TYPE PLUMBING
J 0
(-6000 4025);
DISPLAY 0.872340 (-6000 4025);
PAINT GREEN (-6000 4025);
DISPLAY INVISIBLE (-6000 4025);
FORCEPROP 1 LAST HDL_TAP TRUE
J 0
(-5675 3850);
DISPLAY 0.872340 (-5675 3850);
DISPLAY INVISIBLE (-5675 3850);
FORCEPROP 1 LAST PATH I96
J 0
(-6002 3975);
DISPLAY 0.872340 (-6002 3975);
PAINT GREEN (-6002 3975);
DISPLAY INVISIBLE (-6002 3975);
FORCEADD TAP..1
(-6000 4025);
FORCEPROP 3 LASTPIN (-6050 4025) SIG_NAME M_K_CPU1_SA_DQ<5>
J 0
(-6040 4035);
DISPLAY 0.659574 (-6040 4035);
PAINT MONO (-6040 4035);
DISPLAY INVISIBLE (-6040 4035);
FORCEPROP 1 LASTPIN (-6050 4025) BN 5
J 0
(-6062 4033);
DISPLAY 0.489362 (-6062 4033);
PAINT GREEN (-6062 4033);
FORCEPROP 2 LAST CDS_LIB mstr_standard
J 0
(-6000 4025);
DISPLAY 0.723404 (-6000 4025);
PAINT MONO (-6000 4025);
DISPLAY INVISIBLE (-6000 4025);
FORCEPROP 1 LAST BODY_TYPE PLUMBING
J 0
(-6000 4075);
DISPLAY 0.872340 (-6000 4075);
PAINT GREEN (-6000 4075);
DISPLAY INVISIBLE (-6000 4075);
FORCEPROP 1 LAST HDL_TAP TRUE
J 0
(-5675 3900);
DISPLAY 0.872340 (-5675 3900);
DISPLAY INVISIBLE (-5675 3900);
FORCEPROP 1 LAST PATH I97
J 0
(-6002 4025);
DISPLAY 0.872340 (-6002 4025);
PAINT GREEN (-6002 4025);
DISPLAY INVISIBLE (-6002 4025);
FORCEADD TAP..1
(-6000 4075);
FORCEPROP 3 LASTPIN (-6050 4075) SIG_NAME M_K_CPU1_SA_DQ<6>
J 0
(-6040 4085);
DISPLAY 0.659574 (-6040 4085);
PAINT MONO (-6040 4085);
DISPLAY INVISIBLE (-6040 4085);
FORCEPROP 1 LASTPIN (-6050 4075) BN 6
J 0
(-6062 4083);
DISPLAY 0.489362 (-6062 4083);
PAINT GREEN (-6062 4083);
FORCEPROP 2 LAST CDS_LIB mstr_standard
J 0
(-6000 4075);
DISPLAY 0.723404 (-6000 4075);
PAINT MONO (-6000 4075);
DISPLAY INVISIBLE (-6000 4075);
FORCEPROP 1 LAST BODY_TYPE PLUMBING
J 0
(-6000 4125);
DISPLAY 0.872340 (-6000 4125);
PAINT GREEN (-6000 4125);
DISPLAY INVISIBLE (-6000 4125);
FORCEPROP 1 LAST HDL_TAP TRUE
J 0
(-5675 3950);
DISPLAY 0.872340 (-5675 3950);
DISPLAY INVISIBLE (-5675 3950);
FORCEPROP 1 LAST PATH I98
J 0
(-6002 4075);
DISPLAY 0.872340 (-6002 4075);
PAINT GREEN (-6002 4075);
DISPLAY INVISIBLE (-6002 4075);
FORCEADD TAP..1
(-6000 4125);
FORCEPROP 3 LASTPIN (-6050 4125) SIG_NAME M_K_CPU1_SA_DQ<7>
J 0
(-6040 4135);
DISPLAY 0.659574 (-6040 4135);
PAINT MONO (-6040 4135);
DISPLAY INVISIBLE (-6040 4135);
FORCEPROP 1 LASTPIN (-6050 4125) BN 7
J 0
(-6062 4133);
DISPLAY 0.489362 (-6062 4133);
PAINT GREEN (-6062 4133);
FORCEPROP 2 LAST CDS_LIB mstr_standard
J 0
(-6000 4125);
DISPLAY 0.723404 (-6000 4125);
PAINT MONO (-6000 4125);
DISPLAY INVISIBLE (-6000 4125);
FORCEPROP 1 LAST BODY_TYPE PLUMBING
J 0
(-6000 4175);
DISPLAY 0.872340 (-6000 4175);
PAINT GREEN (-6000 4175);
DISPLAY INVISIBLE (-6000 4175);
FORCEPROP 1 LAST HDL_TAP TRUE
J 0
(-5675 4000);
DISPLAY 0.872340 (-5675 4000);
DISPLAY INVISIBLE (-5675 4000);
FORCEPROP 1 LAST PATH I99
J 0
(-6002 4125);
DISPLAY 0.872340 (-6002 4125);
PAINT GREEN (-6002 4125);
DISPLAY INVISIBLE (-6002 4125);
FORCEADD QUANTA_TITLE_BLOCK_C..1
(0 0);
FORCEPROP 0 LAST CDS_CON_LAST_MODIFIED Fri Mar 11 14:53:09 2022
J 0
(-1885 15);
DISPLAY INVISIBLE (-1885 15);
FORCEPROP 1 LAST CUSTOM_TXT_CDS <CON_LAST_MODIFIED>
J 0
(-1885 15);
DISPLAY 0.978723 (-1885 15);
FORCEPROP 2 LAST CUSTOM_TXT_CDS <XR_PAGE_TITLE>
J 0
(-7890 5250);
DISPLAY 0.638298 (-7890 5250);
PAINT PINK (-7890 5250);
DISPLAY INVISIBLE (-7890 5250);
FORCEPROP 1 LAST CUSTOM_TXT_CDS <NAME_2>
J 0
(-3175 50);
FORCEPROP 1 LAST CUSTOM_TXT_CDS <NAME_1>
J 0
(-3175 175);
FORCEPROP 1 LAST CUSTOM_TXT_CDS <Q_NUMBER>
J 0
(-1403 103);
DISPLAY 1.212766 (-1403 103);
FORCEPROP 1 LAST CUSTOM_TXT_CDS <Q_PROJ>
J 0
(-2382 102);
DISPLAY 1.212766 (-2382 102);
FORCEPROP 1 LAST CUSTOM_TXT_CDS <Q_REV>
J 0
(-184 103);
DISPLAY 1.212766 (-184 103);
FORCEPROP 1 LAST CUSTOM_TXT_CDS <CON_PAGE_NUM> OF <CON_TOTAL_PAGES>
J 0
(-446 18);
DISPLAY 0.978723 (-446 18);
FORCEPROP 1 LAST Q_TITLE DDR5 - CPU1 CHK
J 0
(-9366 26);
DISPLAY 2.446809 (-9366 26);
PAINT GREEN (-9366 26);
FORCEPROP 1 LAST Q_DEPT BU9
J 1
(-3763 49);
DISPLAY 1.957447 (-3763 49);
PAINT GREEN (-3763 49);
FORCEPROP 2 LAST CDS_LIB pure_quanta
J 0
(0 0);
DISPLAY INVISIBLE (0 0);
FORCEPROP 1 LAST CDS_LMAN_SYM_OUTLINE -9475,6775,100,-125
J 0
(0 0);
DISPLAY 0.468085 (0 0);
PAINT GREEN (0 0);
DISPLAY INVISIBLE (0 0);
FORCEPROP 2 LAST PAGE_BORDER TRUE
J 0
(-7890 5250);
DISPLAY 0.638298 (-7890 5250);
PAINT PINK (-7890 5250);
DISPLAY INVISIBLE (-7890 5250);
FORCEPROP 1 LAST COMMENT_BODY TRUE
J 0
(12 -13);
DISPLAY 0.978723 (12 -13);
PAINT GREEN (12 -13);
DISPLAY INVISIBLE (12 -13);
FORCEPROP 2 LAST CDS_XR_PAGE_TITLE CR-107 : @T6G_MB_LIB.T6G(SCH_1):PAGE107
J 0
(-7890 5250);
DISPLAY 0.638298 (-7890 5250);
PAINT PINK (-7890 5250);
DISPLAY INVISIBLE (-7890 5250);
FORCEADD DNS..2
(-8350 2225);
PAINT RED (-8350 2225);
FORCEPROP 2 LAST CDS_LIB mstr_misc
J 0
(-8350 2225);
DISPLAY INVISIBLE (-8350 2225);
FORCEPROP 1 LAST COMMENT_BODY TRUE
R 1
J 0
(-8275 2000);
DISPLAY 0.872340 (-8275 2000);
PAINT PEACH (-8275 2000);
DISPLAY INVISIBLE (-8275 2000);
WIRE 17 -1 (-5950 5375)(-5950 5350);
WIRE 17 -1 (-5950 5375)(-5375 5375);
FORCEPROP 2 LAST SIG_NAME M_K_CPU1_SA_DQ<31:0>
J 0
(-5885 5385);
DISPLAY 0.489362 (-5885 5385);
WIRE 17 -1 (-7750 3950)(-7750 3900);
WIRE 17 -1 (-7750 3950)(-7750 3975);
WIRE 17 -1 (-7750 3850)(-7750 3900);
WIRE 17 -1 (-7750 3850)(-7750 3800);
WIRE 17 -1 (-7750 3975)(-8250 3975);
FORCEPROP 2 LAST SIG_NAME M_K_CPU1_SA_CB<7:0>
J 0
(-8200 3985);
DISPLAY 0.489362 (-8200 3985);
WIRE 17 -1 (-7750 3750)(-7750 3800);
WIRE 17 -1 (-7750 3700)(-7750 3750);
WIRE 17 -1 (-7750 3650)(-7750 3700);
WIRE 17 -1 (-7750 3600)(-7750 3650);
WIRE 17 -1 (-7750 3500)(-7750 3450);
WIRE 17 -1 (-7750 3500)(-7750 3525);
WIRE 17 -1 (-7750 3400)(-7750 3450);
WIRE 17 -1 (-7750 3400)(-7750 3350);
WIRE 17 -1 (-7750 3525)(-8250 3525);
FORCEPROP 2 LAST SIG_NAME M_K_CPU1_SB_CB<7:0>
J 0
(-8200 3535);
DISPLAY 0.489362 (-8200 3535);
WIRE 17 -1 (-7750 5050)(-7750 5100);
WIRE 17 -1 (-7750 5100)(-7750 5150);
WIRE 17 -1 (-7750 5150)(-7750 5200);
WIRE 17 -1 (-7750 5200)(-7750 5250);
WIRE 17 -1 (-7750 5250)(-7750 5300);
WIRE 17 -1 (-7750 5300)(-7750 5350);
WIRE 17 -1 (-7750 5350)(-7750 5375);
WIRE 17 -1 (-7750 5375)(-8250 5375);
FORCEPROP 2 LAST SIG_NAME M_K_CPU1_SA_CA<6:0>
J 0
(-8235 5385);
DISPLAY 0.489362 (-8235 5385);
WIRE 17 -1 (-7750 4650)(-7750 4700);
WIRE 17 -1 (-7750 4700)(-7750 4750);
WIRE 17 -1 (-7750 4750)(-7750 4800);
WIRE 17 -1 (-7750 4800)(-7750 4850);
WIRE 17 -1 (-7750 4850)(-7750 4900);
WIRE 17 -1 (-7750 4900)(-7750 4950);
WIRE 17 -1 (-7750 4950)(-7750 4975);
WIRE 17 -1 (-7750 4975)(-8250 4975);
FORCEPROP 2 LAST SIG_NAME M_K_CPU1_SB_CA<6:0>
J 0
(-8235 4985);
DISPLAY 0.489362 (-8235 4985);
WIRE 17 -1 (-7750 3300)(-7750 3350);
WIRE 17 -1 (-7750 3250)(-7750 3300);
WIRE 17 -1 (-7750 3200)(-7750 3250);
WIRE 17 -1 (-7750 3150)(-7750 3200);
WIRE 17 -1 (-5950 5300)(-5950 5250);
WIRE 17 -1 (-5950 5350)(-5950 5300);
WIRE 17 -1 (-5950 5250)(-5950 5200);
WIRE 17 -1 (-5950 5200)(-5950 5150);
WIRE 17 -1 (-5950 5150)(-5950 5100);
WIRE 17 -1 (-5950 5100)(-5950 5050);
WIRE 17 -1 (-5950 5050)(-5950 5000);
WIRE 17 -1 (-5950 5000)(-5950 4950);
WIRE 17 -1 (-5950 4950)(-5950 4900);
WIRE 17 -1 (-5950 4900)(-5950 4850);
WIRE 17 -1 (-5950 4850)(-5950 4800);
WIRE 17 -1 (-5950 4800)(-5950 4750);
WIRE 17 -1 (-5950 4750)(-5950 4700);
WIRE 17 -1 (-5950 4700)(-5950 4650);
WIRE 17 -1 (-5950 4650)(-5950 4600);
WIRE 17 -1 (-5950 4550)(-5950 4600);
WIRE 17 -1 (-5950 4500)(-5950 4550);
WIRE 17 -1 (-5950 4450)(-5950 4500);
WIRE 17 -1 (-5950 4400)(-5950 4450);
WIRE 17 -1 (-5950 4400)(-5950 4350);
WIRE 17 -1 (-5950 4350)(-5950 4300);
WIRE 17 -1 (-5950 4300)(-5950 4250);
WIRE 17 -1 (-5950 4250)(-5950 4200);
WIRE 17 -1 (-5950 4200)(-5950 4150);
WIRE 17 -1 (-5950 4150)(-5950 4100);
WIRE 17 -1 (-5950 4100)(-5950 4050);
WIRE 17 -1 (-5950 4050)(-5950 4000);
WIRE 17 -1 (-5950 3950)(-5950 4000);
WIRE 17 -1 (-5950 3900)(-5950 3950);
WIRE 17 -1 (-5950 3850)(-5950 3900);
WIRE 17 -1 (-5950 3800)(-5950 3850);
WIRE 17 -1 (-5950 3700)(-5950 3650);
WIRE 17 -1 (-5950 3725)(-5950 3700);
WIRE 17 -1 (-5950 3650)(-5950 3600);
WIRE 17 -1 (-5950 3600)(-5950 3550);
WIRE 17 -1 (-5950 3725)(-5375 3725);
FORCEPROP 2 LAST SIG_NAME M_K_CPU1_SB_DQ<31:0>
J 0
(-5885 3735);
DISPLAY 0.489362 (-5885 3735);
WIRE 17 -1 (-5950 3550)(-5950 3500);
WIRE 17 -1 (-5950 3500)(-5950 3450);
WIRE 17 -1 (-5950 3450)(-5950 3400);
WIRE 17 -1 (-5950 3400)(-5950 3350);
WIRE 17 -1 (-5950 3350)(-5950 3300);
WIRE 17 -1 (-5950 3300)(-5950 3250);
WIRE 17 -1 (-5950 3250)(-5950 3200);
WIRE 17 -1 (-5950 3200)(-5950 3150);
WIRE 17 -1 (-5950 3150)(-5950 3100);
WIRE 17 -1 (-5950 3100)(-5950 3050);
WIRE 17 -1 (-5950 3050)(-5950 3000);
WIRE 17 -1 (-5950 3000)(-5950 2950);
WIRE 17 -1 (-5950 2900)(-5950 2950);
WIRE 17 -1 (-5950 2850)(-5950 2900);
WIRE 17 -1 (-5950 2800)(-5950 2850);
WIRE 17 -1 (-5950 2750)(-5950 2800);
WIRE 17 -1 (-5950 2750)(-5950 2700);
WIRE 17 -1 (-5950 2700)(-5950 2650);
WIRE 17 -1 (-5950 2650)(-5950 2600);
WIRE 17 -1 (-5950 2600)(-5950 2550);
WIRE 17 -1 (-5950 2550)(-5950 2500);
WIRE 17 -1 (-5950 2500)(-5950 2450);
WIRE 17 -1 (-5950 2450)(-5950 2400);
WIRE 17 -1 (-5950 2400)(-5950 2350);
WIRE 17 -1 (-5950 2300)(-5950 2350);
WIRE 17 -1 (-5950 2250)(-5950 2300);
WIRE 17 -1 (-5950 2200)(-5950 2250);
WIRE 17 -1 (-5950 2150)(-5950 2200);
WIRE 17 -1 (-3225 4275)(-3225 4175);
WIRE 17 -1 (-3225 4375)(-3225 4275);
WIRE 17 -1 (-3225 4175)(-3225 4075);
WIRE 17 -1 (-3225 3975)(-3225 4075);
WIRE 17 -1 (-3225 4475)(-3225 4375);
WIRE 17 -1 (-3225 4500)(-3225 4475);
WIRE 17 -1 (-3225 3875)(-3225 3975);
WIRE 17 -1 (-3225 3775)(-3225 3875);
WIRE 17 -1 (-3225 4500)(-2525 4500);
FORCEPROP 2 LAST SIG_NAME M_K_CPU1_SA_DQS_DN<9:0>
J 0
(-3160 4510);
DISPLAY 0.489362 (-3160 4510);
WIRE 17 -1 (-3425 4325)(-3425 4225);
WIRE 17 -1 (-3425 4425)(-3425 4325);
WIRE 17 -1 (-3425 4225)(-3425 4125);
WIRE 17 -1 (-3425 4025)(-3425 4125);
WIRE 17 -1 (-3425 4525)(-3425 4425);
WIRE 17 -1 (-3425 4550)(-3425 4525);
WIRE 17 -1 (-3425 3925)(-3425 4025);
WIRE 17 -1 (-3425 3825)(-3425 3925);
WIRE 17 -1 (-3425 4550)(-2525 4550);
FORCEPROP 2 LAST SIG_NAME M_K_CPU1_SA_DQS_DP<9:0>
J 0
(-3160 4560);
DISPLAY 0.489362 (-3160 4560);
WIRE 17 -1 (-3425 3375)(-3425 3275);
WIRE 17 -1 (-3425 3475)(-3425 3375);
WIRE 17 -1 (-3425 3275)(-3425 3175);
WIRE 17 -1 (-3425 3175)(-3425 3075);
WIRE 17 -1 (-3425 3500)(-3425 3475);
WIRE 17 -1 (-3425 3500)(-2525 3500);
FORCEPROP 2 LAST SIG_NAME M_K_CPU1_SB_DQS_DP<9:0>
J 0
(-3160 3510);
DISPLAY 0.489362 (-3160 3510);
WIRE 17 -1 (-3225 3325)(-3225 3225);
WIRE 17 -1 (-3225 3425)(-3225 3325);
WIRE 17 -1 (-3225 3225)(-3225 3125);
WIRE 17 -1 (-3225 3125)(-3225 3025);
WIRE 17 -1 (-3225 3450)(-3225 3425);
WIRE 17 -1 (-3225 3450)(-2525 3450);
FORCEPROP 2 LAST SIG_NAME M_K_CPU1_SB_DQS_DN<9:0>
J 0
(-3160 3460);
DISPLAY 0.489362 (-3160 3460);
WIRE 17 -1 (-3425 2975)(-3425 3075);
WIRE 17 -1 (-3425 2875)(-3425 2975);
WIRE 17 -1 (-3425 2775)(-3425 2875);
WIRE 17 -1 (-3225 3675)(-3225 3575);
WIRE 17 -1 (-3225 3775)(-3225 3675);
WIRE 17 -1 (-3425 3725)(-3425 3625);
WIRE 17 -1 (-3425 3825)(-3425 3725);
WIRE 17 -1 (-3225 2625)(-3225 2525);
WIRE 17 -1 (-3225 2725)(-3225 2625);
WIRE 17 -1 (-3225 2725)(-3225 2825);
WIRE 17 -1 (-3225 2825)(-3225 2925);
WIRE 17 -1 (-3225 2925)(-3225 3025);
WIRE 17 -1 (-3425 2675)(-3425 2575);
WIRE 17 -1 (-3425 2775)(-3425 2675);
WIRE 16 -1 (-6400 925)(-6400 1000);
WIRE 16 -1 (-8675 2975)(-8675 3050);
WIRE 16 -1 (-8375 2325)(-8375 2350);
WIRE 16 -1 (-7850 2625)(-8300 2625);
FORCEPROP 2 LAST SIG_NAME I3C_SPD_DDRGL_CPU1_SCL
J 0
(-8335 2635);
DISPLAY 0.489362 (-8335 2635);
WIRE 16 -1 (-7450 2725)(-7550 2725);
FORCEPROP 2 LAST SIG_NAME I3C_SPD_DDRK_CPU1_SCL
J 0
(-7935 2735);
DISPLAY 0.446809 (-7935 2735);
FORCEPROP 2 LASTPROP $XRERR UNIQUE?
J 0
(-8175 2735);
DISPLAY 0.638298 (-8175 2735);
PAINT MONO (-8175 2735);
DISPLAY INVISIBLE (-8175 2735);
WIRE 16 -1 (-7550 2725)(-7550 2625);
WIRE 16 -1 (-7550 2625)(-7650 2625);
WIRE 16 -1 (-8150 2075)(-8375 2075);
WIRE 16 -1 (-8150 2075)(-8150 2475);
WIRE 16 -1 (-8375 2125)(-8375 2075);
WIRE 16 -1 (-8375 2075)(-8400 2075);
WIRE 16 -1 (-7450 2475)(-8150 2475);
FORCEPROP 2 LAST SIG_NAME PWRGD_CHK_CPU1_DIMM
J 0
(-8035 2485);
DISPLAY 0.489362 (-8035 2485);
FORCEPROP 2 LASTPROP $XRERR UNIQUE?
J 0
(-8275 2485);
DISPLAY 0.638298 (-8275 2485);
PAINT MONO (-8275 2485);
DISPLAY INVISIBLE (-8275 2485);
WIRE 16 -1 (-7450 2325)(-8025 2325);
FORCEPROP 2 LAST SIG_NAME TP_CHK_CPU1_DIMM_RFU_5
J 0
(-8035 2335);
DISPLAY 0.489362 (-8035 2335);
FORCEPROP 2 LASTPROP $XRERR UNIQUE?
J 0
(-8265 2325);
DISPLAY 0.638298 (-8265 2325);
PAINT MONO (-8265 2325);
DISPLAY INVISIBLE (-8265 2325);
WIRE 16 -1 (-7450 2275)(-8025 2275);
FORCEPROP 2 LAST SIG_NAME TP_CHK_CPU1_DIMM_RFU_4
J 0
(-8035 2285);
DISPLAY 0.489362 (-8035 2285);
FORCEPROP 2 LASTPROP $XRERR UNIQUE?
J 0
(-8265 2275);
DISPLAY 0.638298 (-8265 2275);
PAINT MONO (-8265 2275);
DISPLAY INVISIBLE (-8265 2275);
WIRE 16 -1 (-7450 2225)(-8025 2225);
FORCEPROP 2 LAST SIG_NAME TP_CHK_CPU1_DIMM_RFU_3
J 0
(-8035 2235);
DISPLAY 0.489362 (-8035 2235);
FORCEPROP 2 LASTPROP $XRERR UNIQUE?
J 0
(-8265 2225);
DISPLAY 0.638298 (-8265 2225);
PAINT MONO (-8265 2225);
DISPLAY INVISIBLE (-8265 2225);
WIRE 16 -1 (-7450 2175)(-8025 2175);
FORCEPROP 2 LAST SIG_NAME TP_CHK_CPU1_DIMM_RFU_2
J 0
(-8035 2185);
DISPLAY 0.489362 (-8035 2185);
FORCEPROP 2 LASTPROP $XRERR UNIQUE?
J 0
(-8265 2175);
DISPLAY 0.638298 (-8265 2175);
PAINT MONO (-8265 2175);
DISPLAY INVISIBLE (-8265 2175);
WIRE 16 -1 (-7450 2375)(-8025 2375);
FORCEPROP 2 LAST SIG_NAME TP_CHK_CPU1_DIMM_RFU_6
J 0
(-8035 2385);
DISPLAY 0.489362 (-8035 2385);
FORCEPROP 2 LASTPROP $XRERR UNIQUE?
J 0
(-8265 2375);
DISPLAY 0.638298 (-8265 2375);
PAINT MONO (-8265 2375);
DISPLAY INVISIBLE (-8265 2375);
WIRE 16 -1 (-7450 2775)(-8250 2775);
FORCEPROP 2 LAST SIG_NAME I3C_SPD_DDRGL_CPU1_SDA
J 0
(-8260 2785);
DISPLAY 0.489362 (-8260 2785);
WIRE 16 -1 (-7450 2825)(-8250 2825);
FORCEPROP 2 LAST SIG_NAME PD_CHK_CPU1_DIMM_SAA
J 0
(-8225 2835);
DISPLAY 0.489362 (-8225 2835);
WIRE 16 -1 (-8575 2875)(-7450 2875);
WIRE 16 -1 (-8575 3275)(-8575 2875);
WIRE 16 -1 (-8575 3300)(-8575 3275);
WIRE 16 -1 (-8675 3275)(-8575 3275);
WIRE 16 -1 (-8675 3250)(-8675 3275);
WIRE 16 -1 (-7450 2075)(-8025 2075);
FORCEPROP 2 LAST SIG_NAME TP_CHK_CPU1_DIMM_RFU_0
J 0
(-8035 2085);
DISPLAY 0.489362 (-8035 2085);
FORCEPROP 2 LASTPROP $XRERR UNIQUE?
J 0
(-8265 2075);
DISPLAY 0.638298 (-8265 2075);
PAINT MONO (-8265 2075);
DISPLAY INVISIBLE (-8265 2075);
WIRE 16 -1 (-7450 2125)(-8025 2125);
FORCEPROP 2 LAST SIG_NAME TP_CHK_CPU1_DIMM_RFU_1
J 0
(-8035 2135);
DISPLAY 0.489362 (-8035 2135);
FORCEPROP 2 LASTPROP $XRERR UNIQUE?
J 0
(-8265 2125);
DISPLAY 0.638298 (-8265 2125);
PAINT MONO (-8265 2125);
DISPLAY INVISIBLE (-8265 2125);
WIRE 16 -1 (-7450 2975)(-8100 2975);
FORCEPROP 2 LAST SIG_NAME M_K_CPU1_ALERT_N
J 0
(-8085 2985);
DISPLAY 0.489362 (-8085 2985);
WIRE 16 -1 (-7450 3025)(-8100 3025);
FORCEPROP 2 LAST SIG_NAME M_K_CPU1_RESET_N
J 0
(-8085 3035);
DISPLAY 0.489362 (-8085 3035);
WIRE 16 -1 (-2150 5175)(-1850 5175);
WIRE 16 -1 (-2150 5225)(-2150 5175);
WIRE 16 -1 (-1850 5225)(-2150 5225);
WIRE 16 -1 (-2150 5225)(-2150 5275);
WIRE 16 -1 (-1850 5275)(-2150 5275);
WIRE 16 -1 (-2150 5275)(-2150 6025);
WIRE 16 -1 (-2275 6025)(-2150 6025);
WIRE 16 -1 (-2275 6025)(-2850 6025);
WIRE 16 -1 (-2275 6025)(-2275 5925);
WIRE 16 -1 (-2850 6025)(-2850 6100);
WIRE 16 -1 (-2850 5925)(-2850 6025);
WIRE 16 -1 (-350 5275)(-350 5225);
WIRE 16 -1 (-350 5275)(-650 5275);
WIRE 16 -1 (-350 5225)(-350 5175);
WIRE 16 -1 (-350 5225)(-650 5225);
WIRE 16 -1 (-350 5175)(-350 5125);
WIRE 16 -1 (-350 5175)(-650 5175);
WIRE 16 -1 (-350 5125)(-650 5125);
WIRE 16 -1 (-350 5125)(-350 5075);
WIRE 16 -1 (-350 5075)(-350 5025);
WIRE 16 -1 (-350 5075)(-650 5075);
WIRE 16 -1 (-350 5025)(-350 4975);
WIRE 16 -1 (-350 5025)(-650 5025);
WIRE 16 -1 (-350 4975)(-350 4925);
WIRE 16 -1 (-350 4975)(-650 4975);
WIRE 16 -1 (-350 4925)(-350 4875);
WIRE 16 -1 (-350 4925)(-650 4925);
WIRE 16 -1 (-350 4875)(-350 4825);
WIRE 16 -1 (-350 4875)(-650 4875);
WIRE 16 -1 (-350 4825)(-350 4775);
WIRE 16 -1 (-350 4825)(-650 4825);
WIRE 16 -1 (-350 4775)(-350 4725);
WIRE 16 -1 (-350 4775)(-650 4775);
WIRE 16 -1 (-350 4725)(-350 4675);
WIRE 16 -1 (-350 4725)(-650 4725);
WIRE 16 -1 (-350 4675)(-350 4625);
WIRE 16 -1 (-350 4675)(-650 4675);
WIRE 16 -1 (-350 4625)(-350 4575);
WIRE 16 -1 (-350 4625)(-650 4625);
WIRE 16 -1 (-350 4575)(-350 4525);
WIRE 16 -1 (-350 4575)(-650 4575);
WIRE 16 -1 (-350 4525)(-350 4475);
WIRE 16 -1 (-350 4525)(-650 4525);
WIRE 16 -1 (-350 4475)(-350 4425);
WIRE 16 -1 (-350 4475)(-650 4475);
WIRE 16 -1 (-350 4425)(-350 4375);
WIRE 16 -1 (-350 4425)(-650 4425);
WIRE 16 -1 (-350 4375)(-350 4325);
WIRE 16 -1 (-350 4375)(-650 4375);
WIRE 16 -1 (-350 4325)(-350 4275);
WIRE 16 -1 (-350 4325)(-650 4325);
WIRE 16 -1 (-350 4275)(-350 4225);
WIRE 16 -1 (-350 4275)(-650 4275);
WIRE 16 -1 (-350 4225)(-350 4175);
WIRE 16 -1 (-350 4225)(-650 4225);
WIRE 16 -1 (-350 4175)(-350 4125);
WIRE 16 -1 (-350 4175)(-650 4175);
WIRE 16 -1 (-350 4125)(-650 4125);
WIRE 16 -1 (-350 4125)(-350 4075);
WIRE 16 -1 (-350 4075)(-350 4025);
WIRE 16 -1 (-350 4075)(-650 4075);
WIRE 16 -1 (-350 4025)(-350 3975);
WIRE 16 -1 (-350 4025)(-650 4025);
WIRE 16 -1 (-350 3975)(-350 3925);
WIRE 16 -1 (-350 3975)(-650 3975);
WIRE 16 -1 (-350 3925)(-350 3875);
WIRE 16 -1 (-350 3925)(-650 3925);
WIRE 16 -1 (-350 3875)(-350 3825);
WIRE 16 -1 (-350 3875)(-650 3875);
WIRE 16 -1 (-350 3825)(-350 3775);
WIRE 16 -1 (-350 3825)(-650 3825);
WIRE 16 -1 (-350 3775)(-350 3725);
WIRE 16 -1 (-350 3775)(-650 3775);
WIRE 16 -1 (-350 3725)(-350 3675);
WIRE 16 -1 (-350 3725)(-650 3725);
WIRE 16 -1 (-350 3675)(-350 3625);
WIRE 16 -1 (-350 3675)(-650 3675);
WIRE 16 -1 (-350 3625)(-350 3575);
WIRE 16 -1 (-350 3625)(-650 3625);
WIRE 16 -1 (-350 3575)(-350 3525);
WIRE 16 -1 (-350 3575)(-650 3575);
WIRE 16 -1 (-350 3525)(-350 3475);
WIRE 16 -1 (-350 3525)(-650 3525);
WIRE 16 -1 (-350 3475)(-350 3425);
WIRE 16 -1 (-350 3475)(-650 3475);
WIRE 16 -1 (-350 3425)(-350 3375);
WIRE 16 -1 (-350 3425)(-650 3425);
WIRE 16 -1 (-350 3375)(-350 3325);
WIRE 16 -1 (-350 3375)(-650 3375);
WIRE 16 -1 (-350 3325)(-350 3275);
WIRE 16 -1 (-350 3325)(-650 3325);
WIRE 16 -1 (-350 3275)(-350 3225);
WIRE 16 -1 (-350 3275)(-650 3275);
WIRE 16 -1 (-350 3225)(-350 3175);
WIRE 16 -1 (-350 3225)(-650 3225);
WIRE 16 -1 (-350 3175)(-350 3125);
WIRE 16 -1 (-350 3175)(-650 3175);
WIRE 16 -1 (-350 3125)(-350 3075);
WIRE 16 -1 (-350 3125)(-650 3125);
WIRE 16 -1 (-350 3075)(-650 3075);
WIRE 16 -1 (-350 3075)(-350 3025);
WIRE 16 -1 (-350 3025)(-350 2975);
WIRE 16 -1 (-350 3025)(-650 3025);
WIRE 16 -1 (-350 2975)(-350 2925);
WIRE 16 -1 (-350 2975)(-650 2975);
WIRE 16 -1 (-350 2925)(-350 2875);
WIRE 16 -1 (-350 2925)(-650 2925);
WIRE 16 -1 (-350 2875)(-350 2825);
WIRE 16 -1 (-350 2875)(-650 2875);
WIRE 16 -1 (-350 2825)(-350 2775);
WIRE 16 -1 (-350 2825)(-650 2825);
WIRE 16 -1 (-350 2775)(-350 2725);
WIRE 16 -1 (-350 2775)(-650 2775);
WIRE 16 -1 (-350 2725)(-350 2675);
WIRE 16 -1 (-350 2725)(-650 2725);
WIRE 16 -1 (-350 2675)(-350 2625);
WIRE 16 -1 (-350 2675)(-650 2675);
WIRE 16 -1 (-350 2625)(-350 2575);
WIRE 16 -1 (-350 2625)(-650 2625);
WIRE 16 -1 (-350 2575)(-350 2525);
WIRE 16 -1 (-350 2575)(-650 2575);
WIRE 16 -1 (-350 2525)(-350 2475);
WIRE 16 -1 (-350 2525)(-650 2525);
WIRE 16 -1 (-350 2475)(-350 2425);
WIRE 16 -1 (-350 2475)(-650 2475);
WIRE 16 -1 (-350 2425)(-350 2375);
WIRE 16 -1 (-350 2425)(-650 2425);
WIRE 16 -1 (-350 2375)(-350 2325);
WIRE 16 -1 (-350 2375)(-650 2375);
WIRE 16 -1 (-350 2325)(-350 2275);
WIRE 16 -1 (-350 2325)(-650 2325);
WIRE 16 -1 (-350 2275)(-350 2225);
WIRE 16 -1 (-350 2275)(-650 2275);
WIRE 16 -1 (-350 2225)(-350 2175);
WIRE 16 -1 (-350 2225)(-650 2225);
WIRE 16 -1 (-350 2175)(-350 2125);
WIRE 16 -1 (-350 2175)(-650 2175);
WIRE 16 -1 (-350 2125)(-350 2025);
WIRE 16 -1 (-350 2125)(-650 2125);
WIRE 16 -1 (-350 2025)(-350 1975);
WIRE 16 -1 (-350 2025)(-650 2025);
WIRE 16 -1 (-350 1975)(-350 1925);
WIRE 16 -1 (-350 1975)(-650 1975);
WIRE 16 -1 (-350 1925)(-350 1675);
WIRE 16 -1 (-350 1925)(-650 1925);
WIRE 16 -1 (-1850 2025)(-2150 2025);
WIRE 16 -1 (-2150 2075)(-2150 2025);
WIRE 16 -1 (-2150 2025)(-2150 1900);
WIRE 16 -1 (-1850 2075)(-2150 2075);
WIRE 16 -1 (-2150 2125)(-2150 2075);
WIRE 16 -1 (-1850 2125)(-2150 2125);
WIRE 16 -1 (-2150 2175)(-2150 2125);
WIRE 16 -1 (-1850 2175)(-2150 2175);
WIRE 16 -1 (-2150 2225)(-2150 2175);
WIRE 16 -1 (-1850 2225)(-2150 2225);
WIRE 16 -1 (-2150 2275)(-2150 2225);
WIRE 16 -1 (-1850 2275)(-2150 2275);
WIRE 16 -1 (-2150 2325)(-2150 2275);
WIRE 16 -1 (-1850 2325)(-2150 2325);
WIRE 16 -1 (-2150 2375)(-2150 2325);
WIRE 16 -1 (-1850 2375)(-2150 2375);
WIRE 16 -1 (-2150 2425)(-2150 2375);
WIRE 16 -1 (-1850 2425)(-2150 2425);
WIRE 16 -1 (-2150 2475)(-2150 2425);
WIRE 16 -1 (-1850 2475)(-2150 2475);
WIRE 16 -1 (-2150 2525)(-2150 2475);
WIRE 16 -1 (-1850 2525)(-2150 2525);
WIRE 16 -1 (-2150 2575)(-2150 2525);
WIRE 16 -1 (-1850 2575)(-2150 2575);
WIRE 16 -1 (-2150 2625)(-2150 2575);
WIRE 16 -1 (-1850 2625)(-2150 2625);
WIRE 16 -1 (-2150 2675)(-2150 2625);
WIRE 16 -1 (-1850 2675)(-2150 2675);
WIRE 16 -1 (-2150 2725)(-2150 2675);
WIRE 16 -1 (-1850 2725)(-2150 2725);
WIRE 16 -1 (-2150 2775)(-2150 2725);
WIRE 16 -1 (-1850 2775)(-2150 2775);
WIRE 16 -1 (-2150 2825)(-2150 2775);
WIRE 16 -1 (-1850 2825)(-2150 2825);
WIRE 16 -1 (-2150 2875)(-2150 2825);
WIRE 16 -1 (-1850 2875)(-2150 2875);
WIRE 16 -1 (-2150 2925)(-2150 2875);
WIRE 16 -1 (-1850 2925)(-2150 2925);
WIRE 16 -1 (-2150 2975)(-2150 2925);
WIRE 16 -1 (-1850 2975)(-2150 2975);
WIRE 16 -1 (-2150 3025)(-2150 2975);
WIRE 16 -1 (-1850 3025)(-2150 3025);
WIRE 16 -1 (-2150 3075)(-2150 3025);
WIRE 16 -1 (-1850 3075)(-2150 3075);
WIRE 16 -1 (-2150 3125)(-2150 3075);
WIRE 16 -1 (-1850 3125)(-2150 3125);
WIRE 16 -1 (-2150 3175)(-2150 3125);
WIRE 16 -1 (-1850 3175)(-2150 3175);
WIRE 16 -1 (-2150 3225)(-2150 3175);
WIRE 16 -1 (-1850 3225)(-2150 3225);
WIRE 16 -1 (-2150 3275)(-2150 3225);
WIRE 16 -1 (-1850 3275)(-2150 3275);
WIRE 16 -1 (-2150 3325)(-2150 3275);
WIRE 16 -1 (-1850 3325)(-2150 3325);
WIRE 16 -1 (-2150 3375)(-2150 3325);
WIRE 16 -1 (-1850 3375)(-2150 3375);
WIRE 16 -1 (-2150 3425)(-2150 3375);
WIRE 16 -1 (-1850 3425)(-2150 3425);
WIRE 16 -1 (-2150 3475)(-2150 3425);
WIRE 16 -1 (-1850 3475)(-2150 3475);
WIRE 16 -1 (-2150 3525)(-2150 3475);
WIRE 16 -1 (-1850 3525)(-2150 3525);
WIRE 16 -1 (-2150 3575)(-2150 3525);
WIRE 16 -1 (-1850 3575)(-2150 3575);
WIRE 16 -1 (-2150 3625)(-2150 3575);
WIRE 16 -1 (-1850 3625)(-2150 3625);
WIRE 16 -1 (-2150 3675)(-2150 3625);
WIRE 16 -1 (-1850 3675)(-2150 3675);
WIRE 16 -1 (-2150 3725)(-2150 3675);
WIRE 16 -1 (-1850 3725)(-2150 3725);
WIRE 16 -1 (-2150 3775)(-2150 3725);
WIRE 16 -1 (-1850 3775)(-2150 3775);
WIRE 16 -1 (-2150 3825)(-2150 3775);
WIRE 16 -1 (-1850 3825)(-2150 3825);
WIRE 16 -1 (-2150 3875)(-2150 3825);
WIRE 16 -1 (-1850 3875)(-2150 3875);
WIRE 16 -1 (-2150 3925)(-2150 3875);
WIRE 16 -1 (-1850 3925)(-2150 3925);
WIRE 16 -1 (-2150 3975)(-2150 3925);
WIRE 16 -1 (-1850 3975)(-2150 3975);
WIRE 16 -1 (-2150 4025)(-2150 3975);
WIRE 16 -1 (-1850 4025)(-2150 4025);
WIRE 16 -1 (-2150 4075)(-2150 4025);
WIRE 16 -1 (-2150 4125)(-2150 4075);
WIRE 16 -1 (-1850 4075)(-2150 4075);
WIRE 16 -1 (-1850 4125)(-2150 4125);
WIRE 16 -1 (-2150 4175)(-2150 4125);
WIRE 16 -1 (-1850 4175)(-2150 4175);
WIRE 16 -1 (-2150 4225)(-2150 4175);
WIRE 16 -1 (-1850 4225)(-2150 4225);
WIRE 16 -1 (-2150 4275)(-2150 4225);
WIRE 16 -1 (-1850 4275)(-2150 4275);
WIRE 16 -1 (-2150 4325)(-2150 4275);
WIRE 16 -1 (-1850 4325)(-2150 4325);
WIRE 16 -1 (-2150 4375)(-2150 4325);
WIRE 16 -1 (-1850 4375)(-2150 4375);
WIRE 16 -1 (-2150 4425)(-2150 4375);
WIRE 16 -1 (-1850 4425)(-2150 4425);
WIRE 16 -1 (-2150 4475)(-2150 4425);
WIRE 16 -1 (-1850 4475)(-2150 4475);
WIRE 16 -1 (-2150 4525)(-2150 4475);
WIRE 16 -1 (-1850 4525)(-2150 4525);
WIRE 16 -1 (-2150 4575)(-2150 4525);
WIRE 16 -1 (-1850 4575)(-2150 4575);
WIRE 16 -1 (-2150 4625)(-2150 4575);
WIRE 16 -1 (-1850 4625)(-2150 4625);
WIRE 16 -1 (-2150 4675)(-2150 4625);
WIRE 16 -1 (-1850 4675)(-2150 4675);
WIRE 16 -1 (-2150 4725)(-2150 4675);
WIRE 16 -1 (-1850 4725)(-2150 4725);
WIRE 16 -1 (-2150 4775)(-2150 4725);
WIRE 16 -1 (-1850 4775)(-2150 4775);
WIRE 16 -1 (-2150 4825)(-2150 4775);
WIRE 16 -1 (-1850 4825)(-2150 4825);
WIRE 16 -1 (-2150 4875)(-2150 4825);
WIRE 16 -1 (-1850 4875)(-2150 4875);
WIRE 16 -1 (-2150 4925)(-2150 4875);
WIRE 16 -1 (-1850 4925)(-2150 4925);
WIRE 16 -1 (-2150 4975)(-2150 4925);
WIRE 16 -1 (-1850 4975)(-2150 4975);
WIRE 16 -1 (-2150 5025)(-2150 4975);
WIRE 16 -1 (-1850 5025)(-2150 5025);
WIRE 16 -1 (-2150 5075)(-2150 5025);
WIRE 16 -1 (-1850 5075)(-2150 5075);
WIRE 16 -1 (-2150 5125)(-2150 5075);
WIRE 16 -1 (-1850 5125)(-2150 5125);
WIRE 16 -1 (-3675 4500)(-3525 4500);
WIRE 16 -1 (-3675 3450)(-3525 3450);
WIRE 16 -1 (-3675 3400)(-3325 3400);
WIRE 16 -1 (-3675 4450)(-3325 4450);
WIRE 16 -1 (-3525 4400)(-3675 4400);
WIRE 16 -1 (-3675 4350)(-3325 4350);
WIRE 16 -1 (-3675 3200)(-3325 3200);
WIRE 16 -1 (-3525 4300)(-3675 4300);
WIRE 16 -1 (-3525 3150)(-3675 3150);
WIRE 16 -1 (-3675 3100)(-3325 3100);
WIRE 16 -1 (-3675 4150)(-3325 4150);
WIRE 16 -1 (-3675 3050)(-3525 3050);
WIRE 16 -1 (-3675 3000)(-3325 3000);
WIRE 16 -1 (-3675 4100)(-3525 4100);
WIRE 16 -1 (-3675 4050)(-3325 4050);
WIRE 16 -1 (-3525 2950)(-3675 2950);
WIRE 16 -1 (-3675 2900)(-3325 2900);
WIRE 16 -1 (-3525 4000)(-3675 4000);
WIRE 16 -1 (-3675 3950)(-3325 3950);
WIRE 16 -1 (-3525 2850)(-3675 2850);
WIRE 16 -1 (-3675 2800)(-3325 2800);
WIRE 16 -1 (-3525 3900)(-3675 3900);
WIRE 16 -1 (-3675 3850)(-3325 3850);
WIRE 16 -1 (-3525 2750)(-3675 2750);
WIRE 16 -1 (-3675 2700)(-3325 2700);
WIRE 16 -1 (-3525 3800)(-3675 3800);
WIRE 16 -1 (-3675 3750)(-3325 3750);
WIRE 16 -1 (-3675 2650)(-3525 2650);
WIRE 16 -1 (-3675 2600)(-3325 2600);
WIRE 16 -1 (-3675 3700)(-3525 3700);
WIRE 16 -1 (-3675 3650)(-3325 3650);
WIRE 16 -1 (-3525 2550)(-3675 2550);
WIRE 16 -1 (-3675 2500)(-3325 2500);
WIRE 16 -1 (-3525 3600)(-3675 3600);
WIRE 16 -1 (-3675 3550)(-3325 3550);
WIRE 16 -1 (-3525 3250)(-3675 3250);
WIRE 16 -1 (-3675 3300)(-3325 3300);
WIRE 16 -1 (-3525 3350)(-3675 3350);
WIRE 16 -1 (-3525 4200)(-3675 4200);
WIRE 16 -1 (-3675 4250)(-3325 4250);
WIRE 16 -1 (-7450 4475)(-8250 4475);
FORCEPROP 2 LAST SIG_NAME M_K_CPU1_SB_PAR
J 0
(-8200 4485);
DISPLAY 0.489362 (-8200 4485);
WIRE 16 -1 (-7450 4525)(-8250 4525);
FORCEPROP 2 LAST SIG_NAME M_K_CPU1_SA_PAR
J 0
(-8200 4535);
DISPLAY 0.489362 (-8200 4535);
WIRE 16 -1 (-7450 1875)(-8250 1875);
FORCEPROP 2 LAST SIG_NAME M_K_CPU1_SB_RSP<0>
J 0
(-8200 1885);
DISPLAY 0.489362 (-8200 1885);
WIRE 16 -1 (-7450 1925)(-8250 1925);
FORCEPROP 2 LAST SIG_NAME M_K_CPU1_SA_RSP<0>
J 0
(-8200 1935);
DISPLAY 0.489362 (-8200 1935);
WIRE 16 -1 (-6050 2125)(-6250 2125);
WIRE 16 -1 (-6050 2175)(-6250 2175);
WIRE 16 -1 (-6050 2225)(-6250 2225);
WIRE 16 -1 (-6250 2275)(-6050 2275);
WIRE 16 -1 (-6050 2325)(-6250 2325);
WIRE 16 -1 (-6050 2375)(-6250 2375);
WIRE 16 -1 (-6050 2425)(-6250 2425);
WIRE 16 -1 (-6250 2475)(-6050 2475);
WIRE 16 -1 (-6050 2525)(-6250 2525);
WIRE 16 -1 (-6050 2575)(-6250 2575);
WIRE 16 -1 (-6050 2625)(-6250 2625);
WIRE 16 -1 (-6250 2675)(-6050 2675);
WIRE 16 -1 (-6050 2725)(-6250 2725);
WIRE 16 -1 (-6050 2775)(-6250 2775);
WIRE 16 -1 (-6050 2825)(-6250 2825);
WIRE 16 -1 (-6250 2875)(-6050 2875);
WIRE 16 -1 (-6050 2925)(-6250 2925);
WIRE 16 -1 (-6050 2975)(-6250 2975);
WIRE 16 -1 (-6050 3025)(-6250 3025);
WIRE 16 -1 (-6250 3075)(-6050 3075);
WIRE 16 -1 (-6050 3125)(-6250 3125);
WIRE 16 -1 (-6050 3175)(-6250 3175);
WIRE 16 -1 (-6050 3225)(-6250 3225);
WIRE 16 -1 (-6250 3275)(-6050 3275);
WIRE 16 -1 (-6050 3325)(-6250 3325);
WIRE 16 -1 (-6050 3375)(-6250 3375);
WIRE 16 -1 (-6050 3425)(-6250 3425);
WIRE 16 -1 (-6250 3475)(-6050 3475);
WIRE 16 -1 (-6050 3525)(-6250 3525);
WIRE 16 -1 (-6050 3575)(-6250 3575);
WIRE 16 -1 (-6050 3625)(-6250 3625);
WIRE 16 -1 (-6250 3675)(-6050 3675);
WIRE 16 -1 (-6050 3775)(-6250 3775);
WIRE 16 -1 (-6050 3825)(-6250 3825);
WIRE 16 -1 (-6050 3875)(-6250 3875);
WIRE 16 -1 (-6250 3925)(-6050 3925);
WIRE 16 -1 (-6050 3975)(-6250 3975);
WIRE 16 -1 (-6050 4025)(-6250 4025);
WIRE 16 -1 (-6050 4075)(-6250 4075);
WIRE 16 -1 (-6250 4125)(-6050 4125);
WIRE 16 -1 (-6050 4175)(-6250 4175);
WIRE 16 -1 (-6050 4225)(-6250 4225);
WIRE 16 -1 (-6050 4275)(-6250 4275);
WIRE 16 -1 (-6250 4325)(-6050 4325);
WIRE 16 -1 (-6050 4375)(-6250 4375);
WIRE 16 -1 (-6050 4425)(-6250 4425);
WIRE 16 -1 (-6050 4475)(-6250 4475);
WIRE 16 -1 (-6250 4525)(-6050 4525);
WIRE 16 -1 (-6050 4575)(-6250 4575);
WIRE 16 -1 (-6050 4625)(-6250 4625);
WIRE 16 -1 (-6050 4675)(-6250 4675);
WIRE 16 -1 (-6250 4725)(-6050 4725);
WIRE 16 -1 (-6050 4775)(-6250 4775);
WIRE 16 -1 (-6050 4825)(-6250 4825);
WIRE 16 -1 (-6050 4875)(-6250 4875);
WIRE 16 -1 (-6250 4925)(-6050 4925);
WIRE 16 -1 (-6050 4975)(-6250 4975);
WIRE 16 -1 (-6050 5025)(-6250 5025);
WIRE 16 -1 (-6050 5075)(-6250 5075);
WIRE 16 -1 (-6250 5125)(-6050 5125);
WIRE 16 -1 (-6050 5175)(-6250 5175);
WIRE 16 -1 (-6050 5225)(-6250 5225);
WIRE 16 -1 (-6050 5275)(-6250 5275);
WIRE 16 -1 (-7450 4225)(-8250 4225);
FORCEPROP 2 LAST SIG_NAME M_K_CPU1_SB_CS_N<1>
J 0
(-8200 4235);
DISPLAY 0.489362 (-8200 4235);
WIRE 16 -1 (-7450 4375)(-8250 4375);
FORCEPROP 2 LAST SIG_NAME M_K_CPU1_SA_CS_N<1>
J 0
(-8200 4385);
DISPLAY 0.489362 (-8200 4385);
WIRE 16 -1 (-7450 4175)(-8250 4175);
FORCEPROP 2 LAST SIG_NAME M_K_CPU1_SB_CS_N<0>
J 0
(-8200 4185);
DISPLAY 0.489362 (-8200 4185);
WIRE 16 -1 (-7450 4325)(-8250 4325);
FORCEPROP 2 LAST SIG_NAME M_K_CPU1_SA_CS_N<0>
J 0
(-8200 4335);
DISPLAY 0.489362 (-8200 4335);
WIRE 16 -1 (-7450 4075)(-8250 4075);
FORCEPROP 2 LAST SIG_NAME M_K_CPU1_CLK_DP<0>
J 0
(-8200 4085);
DISPLAY 0.489362 (-8200 4085);
WIRE 16 -1 (-7450 4025)(-8250 4025);
FORCEPROP 2 LAST SIG_NAME M_K_CPU1_CLK_DN<0>
J 0
(-8200 4035);
DISPLAY 0.489362 (-8200 4035);
WIRE 16 -1 (-7450 3125)(-7650 3125);
WIRE 16 -1 (-7450 3175)(-7650 3175);
WIRE 16 -1 (-7450 3225)(-7650 3225);
WIRE 16 -1 (-7450 3275)(-7650 3275);
WIRE 16 -1 (-7450 3325)(-7650 3325);
WIRE 16 -1 (-7450 3375)(-7650 3375);
WIRE 16 -1 (-7450 3425)(-7650 3425);
WIRE 16 -1 (-7450 3575)(-7650 3575);
WIRE 16 -1 (-7450 3675)(-7650 3675);
WIRE 16 -1 (-7450 3725)(-7650 3725);
WIRE 16 -1 (-7450 3825)(-7650 3825);
WIRE 16 -1 (-7450 3875)(-7650 3875);
WIRE 16 -1 (-7450 4925)(-7650 4925);
WIRE 16 -1 (-7450 5325)(-7650 5325);
WIRE 16 -1 (-7450 4875)(-7650 4875);
WIRE 16 -1 (-7450 5275)(-7650 5275);
WIRE 16 -1 (-7450 4825)(-7650 4825);
WIRE 16 -1 (-7450 5225)(-7650 5225);
WIRE 16 -1 (-7450 4775)(-7650 4775);
WIRE 16 -1 (-7450 5175)(-7650 5175);
WIRE 16 -1 (-7450 4725)(-7650 4725);
WIRE 16 -1 (-7450 5125)(-7650 5125);
WIRE 16 -1 (-7450 4675)(-7650 4675);
WIRE 16 -1 (-7450 5075)(-7650 5075);
WIRE 16 -1 (-7450 4625)(-7650 4625);
WIRE 16 -1 (-7450 5025)(-7650 5025);
WIRE 16 -1 (-7450 3475)(-7650 3475);
WIRE 16 -1 (-7450 3625)(-7650 3625);
WIRE 16 -1 (-7450 3775)(-7650 3775);
WIRE 16 -1 (-7450 3925)(-7650 3925);
WIRE 16 -1 (-6250 5325)(-6050 5325);
WIRE 16 -1 (-2275 5600)(-2850 5600);
WIRE 16 -1 (-2275 5600)(-2275 5725);
WIRE 16 -1 (-2850 5600)(-2850 5725);
WIRE 16 -1 (-2850 5600)(-2850 5525);
WIRE 16 -1 (-8600 2075)(-8975 2075);
FORCEPROP 2 LAST SIG_NAME PWRGD_CHGL_CPU1
J 0
(-8935 2085);
DISPLAY 0.489362 (-8935 2085);
WIRE 16 -1 (-6400 1275)(-6400 1200);
WIRE 16 -1 (-6400 1275)(-7125 1275);
FORCEPROP 2 LAST SIG_NAME PD_CHK_CPU1_DIMM_SAA
J 0
(-7110 1285);
DISPLAY 0.489362 (-7110 1285);
DOT 1 (-2150 4675);
DOT 1 (-350 5225);
DOT 1 (-350 5175);
DOT 1 (-350 5075);
DOT 1 (-350 5125);
DOT 1 (-350 5025);
DOT 1 (-350 4975);
DOT 1 (-350 4875);
DOT 1 (-350 4825);
DOT 1 (-350 4775);
DOT 1 (-350 4675);
DOT 1 (-350 4725);
DOT 1 (-350 4625);
DOT 1 (-350 4425);
DOT 1 (-350 4375);
DOT 1 (-350 4325);
DOT 1 (-350 4275);
DOT 1 (-350 4175);
DOT 1 (-350 4225);
DOT 1 (-350 4125);
DOT 1 (-350 4075);
DOT 1 (-350 4025);
DOT 1 (-350 3975);
DOT 1 (-350 3925);
DOT 1 (-350 3875);
DOT 1 (-350 3825);
DOT 1 (-350 3775);
DOT 1 (-2150 5275);
DOT 1 (-2150 5225);
DOT 1 (-2150 5075);
DOT 1 (-2150 4925);
DOT 1 (-2150 4875);
DOT 1 (-2150 4825);
DOT 1 (-2150 4775);
DOT 1 (-2150 4725);
DOT 1 (-2150 4625);
DOT 1 (-2150 4575);
DOT 1 (-2150 4525);
DOT 1 (-2150 4425);
DOT 1 (-2150 4475);
DOT 1 (-2150 4375);
DOT 1 (-2150 4325);
DOT 1 (-2150 4275);
DOT 1 (-2150 4225);
DOT 1 (-2150 4175);
DOT 1 (-2150 4125);
DOT 1 (-2150 4075);
DOT 1 (-2150 4025);
DOT 1 (-2150 3975);
DOT 1 (-2150 3925);
DOT 1 (-2150 3875);
DOT 1 (-2150 3775);
DOT 1 (-2150 3825);
DOT 1 (-350 3725);
DOT 1 (-350 3675);
DOT 1 (-350 3625);
DOT 1 (-350 3575);
DOT 1 (-350 3525);
DOT 1 (-350 3475);
DOT 1 (-350 3425);
DOT 1 (-350 3375);
DOT 1 (-350 3275);
DOT 1 (-350 3325);
DOT 1 (-350 3225);
DOT 1 (-350 3175);
DOT 1 (-350 3125);
DOT 1 (-350 3025);
DOT 1 (-350 3075);
DOT 1 (-350 2975);
DOT 1 (-350 2925);
DOT 1 (-350 2875);
DOT 1 (-350 2825);
DOT 1 (-350 2775);
DOT 1 (-350 2725);
DOT 1 (-350 2625);
DOT 1 (-350 2675);
DOT 1 (-350 2575);
DOT 1 (-350 2525);
DOT 1 (-350 2475);
DOT 1 (-350 2375);
DOT 1 (-350 2425);
DOT 1 (-350 2325);
DOT 1 (-350 2275);
DOT 1 (-350 2225);
DOT 1 (-350 2125);
DOT 1 (-350 2175);
DOT 1 (-350 2025);
DOT 1 (-350 1975);
DOT 1 (-350 1925);
DOT 1 (-2150 3725);
DOT 1 (-2150 3675);
DOT 1 (-2150 3625);
DOT 1 (-2150 3575);
DOT 1 (-2150 3525);
DOT 1 (-2150 3475);
DOT 1 (-2150 3425);
DOT 1 (-2150 3375);
DOT 1 (-2150 3325);
DOT 1 (-2150 3275);
DOT 1 (-2150 3225);
DOT 1 (-2150 3175);
DOT 1 (-2150 3125);
DOT 1 (-2150 3075);
DOT 1 (-2150 3025);
DOT 1 (-2150 2975);
DOT 1 (-2150 2925);
DOT 1 (-2150 2875);
DOT 1 (-2150 2825);
DOT 1 (-2150 2775);
DOT 1 (-2150 2725);
DOT 1 (-2150 2625);
DOT 1 (-2150 2675);
DOT 1 (-2150 2575);
DOT 1 (-2150 2525);
DOT 1 (-2150 2475);
DOT 1 (-2150 2375);
DOT 1 (-2150 2425);
DOT 1 (-2150 2325);
DOT 1 (-2150 2275);
DOT 1 (-2150 2225);
DOT 1 (-2150 2125);
DOT 1 (-2150 2175);
DOT 1 (-2150 2075);
DOT 1 (-2150 2025);
DOT 1 (-8575 3275);
DOT 1 (-8375 2075);
DOT 1 (-2850 5600);
DOT 1 (-2850 6025);
DOT 1 (-2275 6025);
DOT 1 (-2150 5025);
DOT 1 (-2150 4975);
DOT 1 (-350 4475);
DOT 1 (-350 4525);
DOT 1 (-350 4575);
DOT 1 (-350 4925);
QUIT
